FILE_TYPE = MACRO_DRAWING;
SET COLOR_WIRE YELLOW;
SET COLOR_PROP ORANGE;
SET COLOR_DOT WHITE;
SET COLOR_ARC YELLOW;
SET COLOR_BODY GREEN;
SET COLOR_NOTE PURPLE;
SET PROP_DISPLAY VALUE;
SET PAGE_NUMBER P202;
FORCEADD LCMXO3LF9400C5BG484C..6
(-2975 1100);
FORCEPROP 1 LAST PART_NUMBER AJ094000T08
J 0
(-3222 2592);
DISPLAY 0.723404 (-3222 2592);
PAINT GREEN (-3222 2592);
DISPLAY INVISIBLE (-3222 2592);
FORCEPROP 1 LAST MATERIAL IC
J 0
(-3222 2465);
DISPLAY 0.723404 (-3222 2465);
PAINT GREEN (-3222 2465);
FORCEPROP 2 LAST PART_TYPE SMLF
J 0
(-3200 2825);
DISPLAY 1.021277 (-3200 2825);
FORCEPROP 2 LAST VALUE LCMXO3LF-9400C-5BG484C
J 0
(-3200 2775);
DISPLAY 1.021277 (-3200 2775);
FORCEPROP 1 LAST $LOCATION U249
J 0
(-3222 2739);
DISPLAY 0.723404 (-3222 2739);
PAINT GREEN (-3222 2739);
FORCEPROP 0 LASTPIN (-2575 2400) $PN A1
J 0
(-2565 2410);
DISPLAY 0.680851 (-2565 2410);
PAINT MONO (-2565 2410);
FORCEPROP 0 LASTPIN (-2575 2350) $PN A22
J 0
(-2565 2360);
DISPLAY 0.680851 (-2565 2360);
PAINT MONO (-2565 2360);
FORCEPROP 0 LASTPIN (-2575 2300) $PN B7
J 0
(-2565 2310);
DISPLAY 0.680851 (-2565 2310);
PAINT MONO (-2565 2310);
FORCEPROP 0 LASTPIN (-2575 2250) $PN B16
J 0
(-2565 2260);
DISPLAY 0.680851 (-2565 2260);
PAINT MONO (-2565 2260);
FORCEPROP 0 LASTPIN (-2575 2200) $PN C2
J 0
(-2565 2210);
DISPLAY 0.680851 (-2565 2210);
PAINT MONO (-2565 2210);
FORCEPROP 0 LASTPIN (-2575 2150) $PN C11
J 0
(-2565 2160);
DISPLAY 0.680851 (-2565 2160);
PAINT MONO (-2565 2160);
FORCEPROP 0 LASTPIN (-2575 2100) $PN E5
J 0
(-2565 2110);
DISPLAY 0.680851 (-2565 2110);
PAINT MONO (-2565 2110);
FORCEPROP 0 LASTPIN (-2575 2050) $PN E18
J 0
(-2565 2060);
DISPLAY 0.680851 (-2565 2060);
PAINT MONO (-2565 2060);
FORCEPROP 0 LASTPIN (-2575 2000) $PN F2
J 0
(-2565 2010);
DISPLAY 0.680851 (-2565 2010);
PAINT MONO (-2565 2010);
FORCEPROP 0 LASTPIN (-2575 1950) $PN F21
J 0
(-2565 1960);
DISPLAY 0.680851 (-2565 1960);
PAINT MONO (-2565 1960);
FORCEPROP 0 LASTPIN (-2575 1900) $PN H8
J 0
(-2565 1910);
DISPLAY 0.680851 (-2565 1910);
PAINT MONO (-2565 1910);
FORCEPROP 0 LASTPIN (-2575 1850) $PN H10
J 0
(-2565 1860);
DISPLAY 0.680851 (-2565 1860);
PAINT MONO (-2565 1860);
FORCEPROP 0 LASTPIN (-2575 1800) $PN H13
J 0
(-2565 1810);
DISPLAY 0.680851 (-2565 1810);
PAINT MONO (-2565 1810);
FORCEPROP 0 LASTPIN (-2575 1750) $PN H15
J 0
(-2565 1760);
DISPLAY 0.680851 (-2565 1760);
PAINT MONO (-2565 1760);
FORCEPROP 0 LASTPIN (-2575 1700) $PN J9
J 0
(-2565 1710);
DISPLAY 0.680851 (-2565 1710);
PAINT MONO (-2565 1710);
FORCEPROP 0 LASTPIN (-2575 1650) $PN J10
J 0
(-2565 1660);
DISPLAY 0.680851 (-2565 1660);
PAINT MONO (-2565 1660);
FORCEPROP 0 LASTPIN (-2575 1600) $PN J11
J 0
(-2565 1610);
DISPLAY 0.680851 (-2565 1610);
PAINT MONO (-2565 1610);
FORCEPROP 0 LASTPIN (-2575 1550) $PN J12
J 0
(-2565 1560);
DISPLAY 0.680851 (-2565 1560);
PAINT MONO (-2565 1560);
FORCEPROP 0 LASTPIN (-2575 1500) $PN J13
J 0
(-2565 1510);
DISPLAY 0.680851 (-2565 1510);
PAINT MONO (-2565 1510);
FORCEPROP 0 LASTPIN (-2575 1450) $PN J14
J 0
(-2565 1460);
DISPLAY 0.680851 (-2565 1460);
PAINT MONO (-2565 1460);
FORCEPROP 0 LASTPIN (-2575 1400) $PN K9
J 0
(-2565 1410);
DISPLAY 0.680851 (-2565 1410);
PAINT MONO (-2565 1410);
FORCEPROP 0 LASTPIN (-2575 1350) $PN K14
J 0
(-2565 1360);
DISPLAY 0.680851 (-2565 1360);
PAINT MONO (-2565 1360);
FORCEPROP 0 LASTPIN (-2575 1300) $PN K21
J 0
(-2565 1310);
DISPLAY 0.680851 (-2565 1310);
PAINT MONO (-2565 1310);
FORCEPROP 0 LASTPIN (-2575 1250) $PN L2
J 0
(-2565 1260);
DISPLAY 0.680851 (-2565 1260);
PAINT MONO (-2565 1260);
FORCEPROP 0 LASTPIN (-2575 1200) $PN L9
J 0
(-2565 1210);
DISPLAY 0.680851 (-2565 1210);
PAINT MONO (-2565 1210);
FORCEPROP 0 LASTPIN (-2575 1150) $PN L10
J 0
(-2565 1160);
DISPLAY 0.680851 (-2565 1160);
PAINT MONO (-2565 1160);
FORCEPROP 0 LASTPIN (-2575 1100) $PN L13
J 0
(-2565 1110);
DISPLAY 0.680851 (-2565 1110);
PAINT MONO (-2565 1110);
FORCEPROP 0 LASTPIN (-2575 1050) $PN L14
J 0
(-2565 1060);
DISPLAY 0.680851 (-2565 1060);
PAINT MONO (-2565 1060);
FORCEPROP 0 LASTPIN (-2575 1000) $PN L18
J 0
(-2565 1010);
DISPLAY 0.680851 (-2565 1010);
PAINT MONO (-2565 1010);
FORCEPROP 0 LASTPIN (-2575 950) $PN M4
J 0
(-2565 960);
DISPLAY 0.680851 (-2565 960);
PAINT MONO (-2565 960);
FORCEPROP 0 LASTPIN (-2575 900) $PN M9
J 0
(-2565 910);
DISPLAY 0.680851 (-2565 910);
PAINT MONO (-2565 910);
FORCEPROP 0 LASTPIN (-2575 850) $PN M10
J 0
(-2565 860);
DISPLAY 0.680851 (-2565 860);
PAINT MONO (-2565 860);
FORCEPROP 0 LASTPIN (-2575 800) $PN M13
J 0
(-2565 810);
DISPLAY 0.680851 (-2565 810);
PAINT MONO (-2565 810);
FORCEPROP 0 LASTPIN (-2575 750) $PN M14
J 0
(-2565 760);
DISPLAY 0.680851 (-2565 760);
PAINT MONO (-2565 760);
FORCEPROP 0 LASTPIN (-2575 700) $PN N9
J 0
(-2565 710);
DISPLAY 0.680851 (-2565 710);
PAINT MONO (-2565 710);
FORCEPROP 0 LASTPIN (-2575 650) $PN N14
J 0
(-2565 660);
DISPLAY 0.680851 (-2565 660);
PAINT MONO (-2565 660);
FORCEPROP 0 LASTPIN (-2575 600) $PN N21
J 0
(-2565 610);
DISPLAY 0.680851 (-2565 610);
PAINT MONO (-2565 610);
FORCEPROP 0 LASTPIN (-2575 550) $PN P9
J 0
(-2565 560);
DISPLAY 0.680851 (-2565 560);
PAINT MONO (-2565 560);
FORCEPROP 0 LASTPIN (-2575 500) $PN P10
J 0
(-2565 510);
DISPLAY 0.680851 (-2565 510);
PAINT MONO (-2565 510);
FORCEPROP 0 LASTPIN (-2575 450) $PN P11
J 0
(-2565 460);
DISPLAY 0.680851 (-2565 460);
PAINT MONO (-2565 460);
FORCEPROP 0 LASTPIN (-2575 400) $PN P12
J 0
(-2565 410);
DISPLAY 0.680851 (-2565 410);
PAINT MONO (-2565 410);
FORCEPROP 0 LASTPIN (-2575 350) $PN P13
J 0
(-2565 360);
DISPLAY 0.680851 (-2565 360);
PAINT MONO (-2565 360);
FORCEPROP 0 LASTPIN (-2575 300) $PN P14
J 0
(-2565 310);
DISPLAY 0.680851 (-2565 310);
PAINT MONO (-2565 310);
FORCEPROP 0 LASTPIN (-2575 250) $PN R8
J 0
(-2565 260);
DISPLAY 0.680851 (-2565 260);
PAINT MONO (-2565 260);
FORCEPROP 0 LASTPIN (-2575 200) $PN R15
J 0
(-2565 210);
DISPLAY 0.680851 (-2565 210);
PAINT MONO (-2565 210);
FORCEPROP 0 LASTPIN (-2575 150) $PN V2
J 0
(-2565 160);
DISPLAY 0.680851 (-2565 160);
PAINT MONO (-2565 160);
FORCEPROP 0 LASTPIN (-2575 100) $PN V21
J 0
(-2565 110);
DISPLAY 0.680851 (-2565 110);
PAINT MONO (-2565 110);
FORCEPROP 0 LASTPIN (-2575 50) $PN W12
J 0
(-2565 60);
DISPLAY 0.680851 (-2565 60);
PAINT MONO (-2565 60);
FORCEPROP 0 LASTPIN (-2575 0) $PN Y7
J 0
(-2565 10);
DISPLAY 0.680851 (-2565 10);
PAINT MONO (-2565 10);
FORCEPROP 0 LASTPIN (-2575 -50) $PN Y16
J 0
(-2565 -40);
DISPLAY 0.680851 (-2565 -40);
PAINT MONO (-2565 -40);
FORCEPROP 0 LASTPIN (-2575 -100) $PN AB1
J 0
(-2565 -90);
DISPLAY 0.680851 (-2565 -90);
PAINT MONO (-2565 -90);
FORCEPROP 0 LASTPIN (-2575 -150) $PN AB22
J 0
(-2565 -140);
DISPLAY 0.680851 (-2565 -140);
PAINT MONO (-2565 -140);
FORCEPROP 1 LAST CDS_LMAN_SYM_OUTLINE -250,1350,250,-1350
J 0
(-2975 1100);
DISPLAY 0.468085 (-2975 1100);
PAINT GREEN (-2975 1100);
DISPLAY INVISIBLE (-2975 1100);
FORCEPROP 1 LAST NEEDS_NO_SIZE TRUE
J 0
(-2975 1100);
DISPLAY 0.723404 (-2975 1100);
PAINT GREEN (-2975 1100);
DISPLAY INVISIBLE (-2975 1100);
FORCEPROP 2 LAST CDS_LIB pure_quanta
J 0
(-2975 1100);
DISPLAY INVISIBLE (-2975 1100);
FORCEPROP 1 LAST PATH I1
J 0
(-2975 1100);
DISPLAY 0.723404 (-2975 1100);
PAINT GREEN (-2975 1100);
DISPLAY INVISIBLE (-2975 1100);
FORCEPROP 0 LAST CDS_LOCATION U249
J 0
(-3200 2875);
DISPLAY 1.021277 (-3200 2875);
DISPLAY INVISIBLE (-3200 2875);
FORCEPROP 0 LAST $SEC 6
J 0
(-3200 2875);
DISPLAY 0.680851 (-3200 2875);
PAINT MONO (-3200 2875);
DISPLAY INVISIBLE (-3200 2875);
FORCEPROP 0 LAST CDS_SEC 6
J 0
(-3200 2875);
DISPLAY 1.021277 (-3200 2875);
DISPLAY INVISIBLE (-3200 2875);
FORCEADD UNIVERSAL_GND..1
(1500 825);
FORCEPROP 3 LASTPIN (1500 875) SIG_NAME GND\g
J 0
(1510 885);
DISPLAY 0.659574 (1510 885);
PAINT MONO (1510 885);
DISPLAY INVISIBLE (1510 885);
FORCEPROP 2 LAST CDS_LIB logical_power
J 0
(1500 825);
PAINT MONO (1500 825);
DISPLAY INVISIBLE (1500 825);
FORCEPROP 1 LAST HDL_POWER GND
J 1
(1525 750);
DISPLAY 0.872340 (1525 750);
PAINT GREEN (1525 750);
DISPLAY INVISIBLE (1525 750);
FORCEPROP 1 LAST PATH I10
J 0
(1575 825);
DISPLAY 0.872340 (1575 825);
PAINT AQUA (1575 825);
DISPLAY INVISIBLE (1575 825);
FORCEPROP 2 LAST ROOM IO_SLOT
J 1
(1275 900);
DISPLAY 0.744681 (1275 900);
DISPLAY INVISIBLE (1275 900);
FORCEADD Q_CAP..1
(-4500 -2125);
FORCEPROP 1 LAST PART_NUMBER CH31006KB18
J 0
(-4450 -2275);
DISPLAY 0.404255 (-4450 -2275);
DISPLAY INVISIBLE (-4450 -2275);
FORCEPROP 1 LAST PACK_TYPE C0402
J 0
(-4450 -2325);
DISPLAY 0.638298 (-4450 -2325);
FORCEPROP 1 LAST MATERIAL X7R
J 0
(-4450 -2225);
DISPLAY 0.638298 (-4450 -2225);
FORCEPROP 1 LAST TOLERANCE 10%
J 0
(-4450 -2175);
DISPLAY 0.638298 (-4450 -2175);
FORCEPROP 1 LAST VOLTAGE 50V
J 0
(-4450 -2125);
DISPLAY 0.638298 (-4450 -2125);
FORCEPROP 1 LAST VALUE 0.01UF
J 0
(-4450 -2075);
DISPLAY 0.638298 (-4450 -2075);
FORCEPROP 1 LAST $LOCATION C1124
J 0
(-4450 -2025);
DISPLAY 0.638298 (-4450 -2025);
FORCEPROP 1 LASTPIN (-4500 -2025) $PN 1
J 0
(-4490 -2045);
DISPLAY 0.787234 (-4490 -2045);
PAINT MONO (-4490 -2045);
FORCEPROP 1 LASTPIN (-4500 -2225) $PN 2
J 0
(-4490 -2245);
DISPLAY 0.787234 (-4490 -2245);
PAINT MONO (-4490 -2245);
FORCEPROP 2 LAST CDS_LIB pure_quanta
J 0
(-4500 -2125);
DISPLAY INVISIBLE (-4500 -2125);
FORCEPROP 1 LAST PATH I100
J 0
(-4450 -1975);
DISPLAY 0.978723 (-4450 -1975);
PAINT WHITE (-4450 -1975);
DISPLAY INVISIBLE (-4450 -1975);
FORCEPROP 2 LAST CDS_LOCATION C1124
J 0
(-4450 -1925);
DISPLAY 1.021277 (-4450 -1925);
DISPLAY INVISIBLE (-4450 -1925);
FORCEPROP 0 LAST $SEC 1
J 0
(-4450 -1975);
DISPLAY 0.680851 (-4450 -1975);
PAINT MONO (-4450 -1975);
DISPLAY INVISIBLE (-4450 -1975);
FORCEPROP 2 LAST CDS_SEC 1
J 0
(-4450 -1925);
DISPLAY 1.021277 (-4450 -1925);
DISPLAY INVISIBLE (-4450 -1925);
FORCEADD Q_CAP..1
(-4800 -2125);
FORCEPROP 1 LAST PART_NUMBER CH4104K1B00
J 0
(-4750 -2325);
DISPLAY 0.787234 (-4750 -2325);
DISPLAY INVISIBLE (-4750 -2325);
FORCEPROP 1 LAST PACK_TYPE 0402
J 0
(-4750 -2275);
DISPLAY 0.787234 (-4750 -2275);
FORCEPROP 1 LAST MATERIAL X7R
J 0
(-4750 -2225);
DISPLAY 0.787234 (-4750 -2225);
FORCEPROP 1 LAST TOLERANCE 10%
J 0
(-4750 -2175);
DISPLAY 0.787234 (-4750 -2175);
FORCEPROP 1 LAST VALUE 0.1UF
J 0
(-4750 -2075);
DISPLAY 0.787234 (-4750 -2075);
FORCEPROP 1 LAST VOLTAGE 25V
J 0
(-4750 -2125);
DISPLAY 0.787234 (-4750 -2125);
FORCEPROP 1 LAST $LOCATION C1941
J 0
(-4750 -2025);
DISPLAY 0.978723 (-4750 -2025);
FORCEPROP 1 LASTPIN (-4800 -2025) $PN 1
J 0
(-4790 -2045);
DISPLAY 0.787234 (-4790 -2045);
PAINT MONO (-4790 -2045);
FORCEPROP 1 LASTPIN (-4800 -2225) $PN 2
J 0
(-4790 -2245);
DISPLAY 0.787234 (-4790 -2245);
PAINT MONO (-4790 -2245);
FORCEPROP 2 LAST CDS_LIB pure_quanta
J 0
(-4800 -2125);
DISPLAY INVISIBLE (-4800 -2125);
FORCEPROP 1 LAST PATH I101
J 0
(-4750 -1975);
DISPLAY 0.978723 (-4750 -1975);
PAINT WHITE (-4750 -1975);
DISPLAY INVISIBLE (-4750 -1975);
FORCEPROP 0 LAST CDS_LOCATION C1941
J 0
(-4750 -1975);
DISPLAY 1.021277 (-4750 -1975);
DISPLAY INVISIBLE (-4750 -1975);
FORCEPROP 0 LAST $SEC 1
J 0
(-4750 -1975);
DISPLAY 0.680851 (-4750 -1975);
PAINT MONO (-4750 -1975);
DISPLAY INVISIBLE (-4750 -1975);
FORCEPROP 0 LAST CDS_SEC 1
J 0
(-4750 -1975);
DISPLAY 1.021277 (-4750 -1975);
DISPLAY INVISIBLE (-4750 -1975);
FORCEADD LCMXO3LF9400C5BG484C..5
(-4950 1400);
FORCEPROP 1 LAST PART_NUMBER AJ094000T08
J 0
(-5347 2544);
DISPLAY 0.723404 (-5347 2544);
PAINT GREEN (-5347 2544);
DISPLAY INVISIBLE (-5347 2544);
FORCEPROP 2 LAST PART_TYPE SMLF
J 0
(-5325 2775);
DISPLAY 1.021277 (-5325 2775);
FORCEPROP 1 LAST MATERIAL IC
J 0
(-5347 2417);
DISPLAY 0.723404 (-5347 2417);
PAINT GREEN (-5347 2417);
FORCEPROP 2 LAST VALUE LCMXO3LF-9400C-5BG484C
J 0
(-5325 2725);
DISPLAY 1.021277 (-5325 2725);
FORCEPROP 1 LAST $LOCATION U249
J 0
(-5347 2691);
DISPLAY 0.723404 (-5347 2691);
PAINT GREEN (-5347 2691);
FORCEPROP 0 LASTPIN (-5500 2350) $PN K10
J 2
(-5510 2360);
DISPLAY 0.680851 (-5510 2360);
PAINT MONO (-5510 2360);
FORCEPROP 0 LASTPIN (-5500 2300) $PN K11
J 2
(-5510 2310);
DISPLAY 0.680851 (-5510 2310);
PAINT MONO (-5510 2310);
FORCEPROP 0 LASTPIN (-5500 2250) $PN K12
J 2
(-5510 2260);
DISPLAY 0.680851 (-5510 2260);
PAINT MONO (-5510 2260);
FORCEPROP 0 LASTPIN (-5500 2200) $PN K13
J 2
(-5510 2210);
DISPLAY 0.680851 (-5510 2210);
PAINT MONO (-5510 2210);
FORCEPROP 0 LASTPIN (-5500 2150) $PN L11
J 2
(-5510 2160);
DISPLAY 0.680851 (-5510 2160);
PAINT MONO (-5510 2160);
FORCEPROP 0 LASTPIN (-5500 2100) $PN L12
J 2
(-5510 2110);
DISPLAY 0.680851 (-5510 2110);
PAINT MONO (-5510 2110);
FORCEPROP 0 LASTPIN (-5500 2050) $PN M11
J 2
(-5510 2060);
DISPLAY 0.680851 (-5510 2060);
PAINT MONO (-5510 2060);
FORCEPROP 0 LASTPIN (-5500 2000) $PN M12
J 2
(-5510 2010);
DISPLAY 0.680851 (-5510 2010);
PAINT MONO (-5510 2010);
FORCEPROP 0 LASTPIN (-5500 1950) $PN N10
J 2
(-5510 1960);
DISPLAY 0.680851 (-5510 1960);
PAINT MONO (-5510 1960);
FORCEPROP 0 LASTPIN (-5500 1900) $PN N11
J 2
(-5510 1910);
DISPLAY 0.680851 (-5510 1910);
PAINT MONO (-5510 1910);
FORCEPROP 0 LASTPIN (-5500 1850) $PN N12
J 2
(-5510 1860);
DISPLAY 0.680851 (-5510 1860);
PAINT MONO (-5510 1860);
FORCEPROP 0 LASTPIN (-5500 1800) $PN N13
J 2
(-5510 1810);
DISPLAY 0.680851 (-5510 1810);
PAINT MONO (-5510 1810);
FORCEPROP 0 LASTPIN (-4400 950) $PN C7
J 0
(-4390 960);
DISPLAY 0.680851 (-4390 960);
PAINT MONO (-4390 960);
FORCEPROP 0 LASTPIN (-4400 900) $PN C12
J 0
(-4390 910);
DISPLAY 0.680851 (-4390 910);
PAINT MONO (-4390 910);
FORCEPROP 0 LASTPIN (-4400 850) $PN C16
J 0
(-4390 860);
DISPLAY 0.680851 (-4390 860);
PAINT MONO (-4390 860);
FORCEPROP 0 LASTPIN (-4400 800) $PN G10
J 0
(-4390 810);
DISPLAY 0.680851 (-4390 810);
PAINT MONO (-4390 810);
FORCEPROP 0 LASTPIN (-4400 750) $PN G13
J 0
(-4390 760);
DISPLAY 0.680851 (-4390 760);
PAINT MONO (-4390 760);
FORCEPROP 0 LASTPIN (-4400 700) $PN H9
J 0
(-4390 710);
DISPLAY 0.680851 (-4390 710);
PAINT MONO (-4390 710);
FORCEPROP 0 LASTPIN (-4400 650) $PN H11
J 0
(-4390 660);
DISPLAY 0.680851 (-4390 660);
PAINT MONO (-4390 660);
FORCEPROP 0 LASTPIN (-4400 600) $PN H12
J 0
(-4390 610);
DISPLAY 0.680851 (-4390 610);
PAINT MONO (-4390 610);
FORCEPROP 0 LASTPIN (-4400 550) $PN H14
J 0
(-4390 560);
DISPLAY 0.680851 (-4390 560);
PAINT MONO (-4390 560);
FORCEPROP 0 LASTPIN (-4400 1650) $PN F20
J 0
(-4390 1660);
DISPLAY 0.680851 (-4390 1660);
PAINT MONO (-4390 1660);
FORCEPROP 0 LASTPIN (-4400 1600) $PN J15
J 0
(-4390 1610);
DISPLAY 0.680851 (-4390 1610);
PAINT MONO (-4390 1610);
FORCEPROP 0 LASTPIN (-4400 1550) $PN K15
J 0
(-4390 1560);
DISPLAY 0.680851 (-4390 1560);
PAINT MONO (-4390 1560);
FORCEPROP 0 LASTPIN (-4400 1500) $PN L15
J 0
(-4390 1510);
DISPLAY 0.680851 (-4390 1510);
PAINT MONO (-4390 1510);
FORCEPROP 0 LASTPIN (-4400 1450) $PN M15
J 0
(-4390 1460);
DISPLAY 0.680851 (-4390 1460);
PAINT MONO (-4390 1460);
FORCEPROP 0 LASTPIN (-4400 1400) $PN M18
J 0
(-4390 1410);
DISPLAY 0.680851 (-4390 1410);
PAINT MONO (-4390 1410);
FORCEPROP 0 LASTPIN (-4400 1350) $PN N15
J 0
(-4390 1360);
DISPLAY 0.680851 (-4390 1360);
PAINT MONO (-4390 1360);
FORCEPROP 0 LASTPIN (-4400 1300) $PN P15
J 0
(-4390 1310);
DISPLAY 0.680851 (-4390 1310);
PAINT MONO (-4390 1310);
FORCEPROP 0 LASTPIN (-4400 1250) $PN V20
J 0
(-4390 1260);
DISPLAY 0.680851 (-4390 1260);
PAINT MONO (-4390 1260);
FORCEPROP 0 LASTPIN (-5500 950) $PN R9
J 2
(-5510 960);
DISPLAY 0.680851 (-5510 960);
PAINT MONO (-5510 960);
FORCEPROP 0 LASTPIN (-5500 900) $PN R10
J 2
(-5510 910);
DISPLAY 0.680851 (-5510 910);
PAINT MONO (-5510 910);
FORCEPROP 0 LASTPIN (-5500 850) $PN R11
J 2
(-5510 860);
DISPLAY 0.680851 (-5510 860);
PAINT MONO (-5510 860);
FORCEPROP 0 LASTPIN (-5500 800) $PN R12
J 2
(-5510 810);
DISPLAY 0.680851 (-5510 810);
PAINT MONO (-5510 810);
FORCEPROP 0 LASTPIN (-5500 750) $PN R13
J 2
(-5510 760);
DISPLAY 0.680851 (-5510 760);
PAINT MONO (-5510 760);
FORCEPROP 0 LASTPIN (-5500 700) $PN R14
J 2
(-5510 710);
DISPLAY 0.680851 (-5510 710);
PAINT MONO (-5510 710);
FORCEPROP 0 LASTPIN (-5500 650) $PN W7
J 2
(-5510 660);
DISPLAY 0.680851 (-5510 660);
PAINT MONO (-5510 660);
FORCEPROP 0 LASTPIN (-5500 600) $PN W11
J 2
(-5510 610);
DISPLAY 0.680851 (-5510 610);
PAINT MONO (-5510 610);
FORCEPROP 0 LASTPIN (-5500 550) $PN W16
J 2
(-5510 560);
DISPLAY 0.680851 (-5510 560);
PAINT MONO (-5510 560);
FORCEPROP 0 LASTPIN (-5500 1150) $PN N8
J 2
(-5510 1160);
DISPLAY 0.680851 (-5510 1160);
PAINT MONO (-5510 1160);
FORCEPROP 0 LASTPIN (-5500 1100) $PN P8
J 2
(-5510 1110);
DISPLAY 0.680851 (-5510 1110);
PAINT MONO (-5510 1110);
FORCEPROP 0 LASTPIN (-5500 1050) $PN V3
J 2
(-5510 1060);
DISPLAY 0.680851 (-5510 1060);
PAINT MONO (-5510 1060);
FORCEPROP 0 LASTPIN (-5500 1450) $PN L8
J 2
(-5510 1460);
DISPLAY 0.680851 (-5510 1460);
PAINT MONO (-5510 1460);
FORCEPROP 0 LASTPIN (-5500 1400) $PN M8
J 2
(-5510 1410);
DISPLAY 0.680851 (-5510 1410);
PAINT MONO (-5510 1410);
FORCEPROP 0 LASTPIN (-5500 1350) $PN M3
J 2
(-5510 1360);
DISPLAY 0.680851 (-5510 1360);
PAINT MONO (-5510 1360);
FORCEPROP 0 LASTPIN (-5500 1650) $PN F3
J 2
(-5510 1660);
DISPLAY 0.680851 (-5510 1660);
PAINT MONO (-5510 1660);
FORCEPROP 0 LASTPIN (-5500 1600) $PN J8
J 2
(-5510 1610);
DISPLAY 0.680851 (-5510 1610);
PAINT MONO (-5510 1610);
FORCEPROP 0 LASTPIN (-5500 1550) $PN K8
J 2
(-5510 1560);
DISPLAY 0.680851 (-5510 1560);
PAINT MONO (-5510 1560);
FORCEPROP 2 LAST CDS_LIB pure_quanta
J 0
(-4950 1400);
DISPLAY INVISIBLE (-4950 1400);
FORCEPROP 1 LAST NEEDS_NO_SIZE TRUE
J 0
(-4950 1400);
DISPLAY 0.723404 (-4950 1400);
PAINT GREEN (-4950 1400);
DISPLAY INVISIBLE (-4950 1400);
FORCEPROP 1 LAST CDS_LMAN_SYM_OUTLINE -400,1000,400,-1000
J 0
(-4950 1400);
DISPLAY 0.468085 (-4950 1400);
PAINT GREEN (-4950 1400);
DISPLAY INVISIBLE (-4950 1400);
FORCEPROP 1 LAST PATH I102
J 0
(-4950 1400);
DISPLAY 0.723404 (-4950 1400);
PAINT GREEN (-4950 1400);
DISPLAY INVISIBLE (-4950 1400);
FORCEPROP 0 LAST CDS_LOCATION U249
J 0
(-5325 2825);
DISPLAY 1.021277 (-5325 2825);
DISPLAY INVISIBLE (-5325 2825);
FORCEPROP 0 LAST $SEC 5
J 0
(-5325 2825);
DISPLAY 0.680851 (-5325 2825);
PAINT MONO (-5325 2825);
DISPLAY INVISIBLE (-5325 2825);
FORCEPROP 0 LAST CDS_SEC 5
J 0
(-5325 2825);
DISPLAY 1.021277 (-5325 2825);
DISPLAY INVISIBLE (-5325 2825);
FORCEADD UNIVERSAL_POWER..1
(-6150 1725);
FORCEPROP 3 LASTPIN (-6150 1675) SIG_NAME P3V3_AUX_FPGA_VCCIO5\g
J 0
(-6140 1685);
DISPLAY 0.659574 (-6140 1685);
PAINT MONO (-6140 1685);
DISPLAY INVISIBLE (-6140 1685);
FORCEPROP 1 LAST HDL_POWER P3V3_AUX_FPGA_VCCIO5
J 1
(-6150 1775);
DISPLAY 0.872340 (-6150 1775);
PAINT GREEN (-6150 1775);
FORCEPROP 2 LAST CDS_LIB logical_power
J 0
(-6150 1725);
DISPLAY INVISIBLE (-6150 1725);
FORCEPROP 1 LAST PATH I103
J 0
(-6100 1750);
DISPLAY 0.872340 (-6100 1750);
PAINT AQUA (-6100 1750);
DISPLAY INVISIBLE (-6100 1750);
FORCEADD UNIVERSAL_POWER..1
(-6150 1525);
FORCEPROP 3 LASTPIN (-6150 1475) SIG_NAME P3V3_AUX_FPGA_VCCIO4\g
J 0
(-6140 1485);
DISPLAY 0.659574 (-6140 1485);
PAINT MONO (-6140 1485);
DISPLAY INVISIBLE (-6140 1485);
FORCEPROP 1 LAST HDL_POWER P3V3_AUX_FPGA_VCCIO4
J 1
(-6150 1575);
DISPLAY 0.872340 (-6150 1575);
PAINT GREEN (-6150 1575);
FORCEPROP 2 LAST CDS_LIB logical_power
J 0
(-6150 1525);
DISPLAY INVISIBLE (-6150 1525);
FORCEPROP 1 LAST PATH I104
J 0
(-6100 1550);
DISPLAY 0.872340 (-6100 1550);
PAINT AQUA (-6100 1550);
DISPLAY INVISIBLE (-6100 1550);
FORCEADD UNIVERSAL_POWER..1
(-6150 1225);
FORCEPROP 3 LASTPIN (-6150 1175) SIG_NAME P3V3_AUX_FPGA_VCCIO3\g
J 0
(-6140 1185);
DISPLAY 0.659574 (-6140 1185);
PAINT MONO (-6140 1185);
DISPLAY INVISIBLE (-6140 1185);
FORCEPROP 1 LAST HDL_POWER P3V3_AUX_FPGA_VCCIO3
J 1
(-6150 1275);
DISPLAY 0.872340 (-6150 1275);
PAINT GREEN (-6150 1275);
FORCEPROP 2 LAST CDS_LIB logical_power
J 0
(-6150 1225);
DISPLAY INVISIBLE (-6150 1225);
FORCEPROP 1 LAST PATH I105
J 0
(-6100 1250);
DISPLAY 0.872340 (-6100 1250);
PAINT AQUA (-6100 1250);
DISPLAY INVISIBLE (-6100 1250);
FORCEADD UNIVERSAL_POWER..1
(-6150 1025);
FORCEPROP 3 LASTPIN (-6150 975) SIG_NAME P3V3_AUX_FPGA_VCCIO2\g
J 0
(-6140 985);
DISPLAY 0.659574 (-6140 985);
PAINT MONO (-6140 985);
DISPLAY INVISIBLE (-6140 985);
FORCEPROP 1 LAST HDL_POWER P3V3_AUX_FPGA_VCCIO2
J 1
(-6150 1075);
DISPLAY 0.872340 (-6150 1075);
PAINT GREEN (-6150 1075);
FORCEPROP 2 LAST CDS_LIB logical_power
J 0
(-6150 1025);
DISPLAY INVISIBLE (-6150 1025);
FORCEPROP 1 LAST PATH I106
J 0
(-6100 1050);
DISPLAY 0.872340 (-6100 1050);
PAINT AQUA (-6100 1050);
DISPLAY INVISIBLE (-6100 1050);
FORCEADD Q_CAP..1
(-5150 -2100);
FORCEPROP 1 LAST PART_NUMBER CH6101MEB01
J 0
(-5100 -2250);
DISPLAY 0.638298 (-5100 -2250);
DISPLAY INVISIBLE (-5100 -2250);
FORCEPROP 1 LAST VALUE 10UF
J 0
(-5100 -2050);
DISPLAY 0.638298 (-5100 -2050);
FORCEPROP 1 LAST PACK_TYPE C0402
J 0
(-5100 -2300);
DISPLAY 0.638298 (-5100 -2300);
FORCEPROP 1 LAST MATERIAL X6S
J 0
(-5100 -2200);
DISPLAY 0.638298 (-5100 -2200);
FORCEPROP 1 LAST TOLERANCE 20%
J 0
(-5100 -2150);
DISPLAY 0.638298 (-5100 -2150);
FORCEPROP 1 LAST VOLTAGE 6.3V
J 0
(-5100 -2100);
DISPLAY 0.638298 (-5100 -2100);
FORCEPROP 1 LAST $LOCATION C1842
J 0
(-5100 -2000);
DISPLAY 0.978723 (-5100 -2000);
FORCEPROP 1 LASTPIN (-5150 -2000) $PN 1
J 0
(-5140 -2020);
DISPLAY 0.787234 (-5140 -2020);
PAINT MONO (-5140 -2020);
FORCEPROP 1 LASTPIN (-5150 -2200) $PN 2
J 0
(-5140 -2220);
DISPLAY 0.787234 (-5140 -2220);
PAINT MONO (-5140 -2220);
FORCEPROP 2 LAST CDS_LIB pure_quanta
J 0
(-5150 -2100);
DISPLAY INVISIBLE (-5150 -2100);
FORCEPROP 1 LAST PATH I107
J 0
(-5100 -1950);
DISPLAY 0.978723 (-5100 -1950);
PAINT WHITE (-5100 -1950);
DISPLAY INVISIBLE (-5100 -1950);
FORCEPROP 0 LAST CDS_LOCATION C1842
J 0
(-5100 -1950);
DISPLAY 1.021277 (-5100 -1950);
DISPLAY INVISIBLE (-5100 -1950);
FORCEPROP 0 LAST $SEC 1
J 0
(-5100 -1950);
DISPLAY 0.680851 (-5100 -1950);
PAINT MONO (-5100 -1950);
DISPLAY INVISIBLE (-5100 -1950);
FORCEPROP 0 LAST CDS_SEC 1
J 0
(-5100 -1950);
DISPLAY 1.021277 (-5100 -1950);
DISPLAY INVISIBLE (-5100 -1950);
FORCEADD Q_RES..1
(-5525 -1925);
FORCEPROP 1 LAST PART_NUMBER CS-1003F900
J 0
(-5675 -1850);
DISPLAY 0.510638 (-5675 -1850);
DISPLAY INVISIBLE (-5675 -1850);
FORCEPROP 1 LAST MATERIAL CHIP
J 0
(-5200 -1925);
DISPLAY 0.638298 (-5200 -1925);
FORCEPROP 1 LAST TOLERANCE 1%
J 0
(-5300 -1925);
DISPLAY 0.638298 (-5300 -1925);
FORCEPROP 1 LAST WATTAGE 1/10W
J 2
(-5350 -1800);
DISPLAY 0.510638 (-5350 -1800);
FORCEPROP 1 LAST PACK_TYPE 0603LF
J 0
(-5675 -1800);
DISPLAY 0.510638 (-5675 -1800);
FORCEPROP 1 LAST VALUE 1
J 2
(-5325 -1925);
DISPLAY 0.638298 (-5325 -1925);
FORCEPROP 1 LAST $LOCATION R3344
J 0
(-5800 -1925);
DISPLAY 0.978723 (-5800 -1925);
FORCEPROP 2 LAST CDS_LIB pure_quanta
J 0
(-5525 -1925);
PAINT MONO (-5525 -1925);
DISPLAY INVISIBLE (-5525 -1925);
FORCEPROP 1 LAST PATH I108
J 0
(-5575 -1775);
DISPLAY 0.978723 (-5575 -1775);
PAINT WHITE (-5575 -1775);
DISPLAY INVISIBLE (-5575 -1775);
FORCEPROP 2 LAST CDS_LOCATION R3344
J 0
(-5575 -1725);
DISPLAY 1.021277 (-5575 -1725);
DISPLAY INVISIBLE (-5575 -1725);
FORCEPROP 2 LAST $SEC 1
J 0
(-5575 -1725);
DISPLAY 0.680851 (-5575 -1725);
PAINT MONO (-5575 -1725);
DISPLAY INVISIBLE (-5575 -1725);
FORCEPROP 2 LAST CDS_SEC 1
J 0
(-5575 -1725);
DISPLAY 1.021277 (-5575 -1725);
DISPLAY INVISIBLE (-5575 -1725);
FORCEPROP 1 LASTPIN (-5625 -1925) $PN 1
J 0
(-5613 -1913);
DISPLAY 0.787234 (-5613 -1913);
DISPLAY INVISIBLE (-5613 -1913);
FORCEPROP 1 LASTPIN (-5425 -1925) $PN 2
J 0
(-5463 -1913);
DISPLAY 0.787234 (-5463 -1913);
DISPLAY INVISIBLE (-5463 -1913);
FORCEADD UNIVERSAL_POWER..1
(-5950 -1775);
FORCEPROP 3 LASTPIN (-5950 -1825) SIG_NAME P3V3_AUX\g
J 0
(-5940 -1815);
DISPLAY 0.659574 (-5940 -1815);
PAINT MONO (-5940 -1815);
DISPLAY INVISIBLE (-5940 -1815);
FORCEPROP 1 LAST HDL_POWER P3V3_AUX
J 1
(-5950 -1725);
DISPLAY 0.872340 (-5950 -1725);
PAINT GREEN (-5950 -1725);
FORCEPROP 2 LAST CDS_LIB logical_power
J 0
(-5950 -1775);
PAINT MONO (-5950 -1775);
DISPLAY INVISIBLE (-5950 -1775);
FORCEPROP 1 LAST PATH I109
J 0
(-5900 -1750);
DISPLAY 0.872340 (-5900 -1750);
PAINT AQUA (-5900 -1750);
DISPLAY INVISIBLE (-5900 -1750);
FORCEADD UNIVERSAL_POWER..1
(1425 500);
FORCEPROP 3 LASTPIN (1425 450) SIG_NAME P3V3_AUX_FPGA_VCCIO1\g
J 0
(1435 460);
DISPLAY 0.659574 (1435 460);
PAINT MONO (1435 460);
DISPLAY INVISIBLE (1435 460);
FORCEPROP 1 LAST HDL_POWER P3V3_AUX_FPGA_VCCIO1
J 1
(1425 550);
DISPLAY 0.872340 (1425 550);
PAINT GREEN (1425 550);
FORCEPROP 2 LAST CDS_LIB logical_power
J 0
(1425 500);
PAINT MONO (1425 500);
DISPLAY INVISIBLE (1425 500);
FORCEPROP 1 LAST PATH I11
J 0
(1475 525);
DISPLAY 0.872340 (1475 525);
PAINT AQUA (1475 525);
DISPLAY INVISIBLE (1475 525);
FORCEADD Q_RES..1
(-1700 2575);
FORCEPROP 1 LAST PART_NUMBER CS-1003F900
J 0
(-1850 2650);
DISPLAY 0.510638 (-1850 2650);
DISPLAY INVISIBLE (-1850 2650);
FORCEPROP 1 LAST VALUE 1
J 2
(-1500 2575);
DISPLAY 0.638298 (-1500 2575);
FORCEPROP 1 LAST TOLERANCE 1%
J 0
(-1475 2575);
DISPLAY 0.638298 (-1475 2575);
FORCEPROP 1 LAST PACK_TYPE 0603LF
J 0
(-1850 2700);
DISPLAY 0.510638 (-1850 2700);
FORCEPROP 1 LAST WATTAGE 1/10W
J 2
(-1525 2700);
DISPLAY 0.510638 (-1525 2700);
FORCEPROP 1 LAST MATERIAL CHIP
J 0
(-1375 2575);
DISPLAY 0.638298 (-1375 2575);
FORCEPROP 1 LAST $LOCATION R3458
J 0
(-1950 2575);
DISPLAY 0.638298 (-1950 2575);
FORCEPROP 1 LASTPIN (-1800 2575) $PN 1
J 0
(-1788 2587);
DISPLAY 0.787234 (-1788 2587);
PAINT MONO (-1788 2587);
FORCEPROP 1 LASTPIN (-1600 2575) $PN 2
J 0
(-1638 2587);
DISPLAY 0.787234 (-1638 2587);
PAINT MONO (-1638 2587);
FORCEPROP 2 LAST CDS_LIB pure_quanta
J 0
(-1700 2575);
DISPLAY INVISIBLE (-1700 2575);
FORCEPROP 1 LAST PATH I119
J 0
(-1750 2725);
DISPLAY 0.978723 (-1750 2725);
PAINT WHITE (-1750 2725);
DISPLAY INVISIBLE (-1750 2725);
FORCEPROP 0 LAST CDS_LOCATION R3458
J 0
(-1525 2725);
DISPLAY 1.021277 (-1525 2725);
DISPLAY INVISIBLE (-1525 2725);
FORCEPROP 0 LAST $SEC 1
J 0
(-1525 2725);
DISPLAY 0.680851 (-1525 2725);
PAINT MONO (-1525 2725);
DISPLAY INVISIBLE (-1525 2725);
FORCEPROP 0 LAST CDS_SEC 1
J 0
(-1525 2725);
DISPLAY 1.021277 (-1525 2725);
DISPLAY INVISIBLE (-1525 2725);
FORCEADD Q_CAP..1
(1425 125);
FORCEPROP 1 LAST PART_NUMBER CH31006KB18
J 0
(1475 -25);
DISPLAY 0.978723 (1475 -25);
DISPLAY INVISIBLE (1475 -25);
FORCEPROP 1 LAST PACK_TYPE C0402
J 0
(1475 -25);
DISPLAY 0.787234 (1475 -25);
FORCEPROP 1 LAST VOLTAGE 50V
J 0
(1475 125);
DISPLAY 0.787234 (1475 125);
FORCEPROP 1 LAST MATERIAL X7R
J 0
(1475 25);
DISPLAY 0.787234 (1475 25);
FORCEPROP 1 LAST TOLERANCE 10%
J 0
(1475 75);
DISPLAY 0.787234 (1475 75);
FORCEPROP 1 LAST VALUE 0.01UF
J 0
(1475 175);
DISPLAY 0.787234 (1475 175);
FORCEPROP 1 LAST $LOCATION C1933
J 0
(1475 225);
DISPLAY 0.787234 (1475 225);
FORCEPROP 1 LASTPIN (1425 225) $PN 1
J 0
(1435 205);
DISPLAY 0.638298 (1435 205);
PAINT MONO (1435 205);
FORCEPROP 1 LASTPIN (1425 25) $PN 2
J 0
(1435 5);
DISPLAY 0.638298 (1435 5);
PAINT MONO (1435 5);
FORCEPROP 2 LAST CDS_LIB pure_quanta
J 0
(1425 125);
DISPLAY INVISIBLE (1425 125);
FORCEPROP 1 LAST PATH I12
J 0
(1475 275);
DISPLAY 0.978723 (1475 275);
PAINT WHITE (1475 275);
DISPLAY INVISIBLE (1475 275);
FORCEPROP 2 LAST CDS_LOCATION C1933
J 0
(1475 325);
DISPLAY 1.021277 (1475 325);
DISPLAY INVISIBLE (1475 325);
FORCEPROP 0 LAST $SEC 1
J 0
(1475 275);
DISPLAY 0.680851 (1475 275);
PAINT MONO (1475 275);
DISPLAY INVISIBLE (1475 275);
FORCEPROP 2 LAST CDS_SEC 1
J 0
(1475 325);
DISPLAY 1.021277 (1475 325);
DISPLAY INVISIBLE (1475 325);
FORCEADD Q_CAP..1
(1700 2375);
FORCEPROP 1 LAST PART_NUMBER CH31006KB18
J 0
(1750 2225);
DISPLAY 0.978723 (1750 2225);
DISPLAY INVISIBLE (1750 2225);
FORCEPROP 1 LAST PACK_TYPE C0402
J 0
(1750 2225);
DISPLAY 0.978723 (1750 2225);
FORCEPROP 1 LAST MATERIAL X7R
J 0
(1750 2275);
DISPLAY 0.978723 (1750 2275);
FORCEPROP 1 LAST TOLERANCE 10%
J 0
(1750 2325);
DISPLAY 0.978723 (1750 2325);
FORCEPROP 1 LAST VOLTAGE 50V
J 0
(1750 2375);
DISPLAY 0.978723 (1750 2375);
FORCEPROP 1 LAST VALUE 0.01UF
J 0
(1750 2425);
DISPLAY 0.978723 (1750 2425);
FORCEPROP 1 LAST $LOCATION C1934
J 0
(1750 2475);
DISPLAY 0.978723 (1750 2475);
FORCEPROP 1 LASTPIN (1700 2475) $PN 1
J 0
(1710 2455);
DISPLAY 0.787234 (1710 2455);
PAINT MONO (1710 2455);
FORCEPROP 1 LASTPIN (1700 2275) $PN 2
J 0
(1710 2255);
DISPLAY 0.787234 (1710 2255);
PAINT MONO (1710 2255);
FORCEPROP 2 LAST CDS_LIB pure_quanta
J 0
(1700 2375);
DISPLAY INVISIBLE (1700 2375);
FORCEPROP 1 LAST PATH I120
J 0
(1750 2525);
DISPLAY 0.978723 (1750 2525);
PAINT WHITE (1750 2525);
DISPLAY INVISIBLE (1750 2525);
FORCEPROP 2 LAST CDS_LOCATION C1934
J 0
(1750 2575);
DISPLAY 1.021277 (1750 2575);
DISPLAY INVISIBLE (1750 2575);
FORCEPROP 0 LAST $SEC 1
J 0
(1750 2525);
DISPLAY 0.680851 (1750 2525);
PAINT MONO (1750 2525);
DISPLAY INVISIBLE (1750 2525);
FORCEPROP 2 LAST CDS_SEC 1
J 0
(1750 2575);
DISPLAY 1.021277 (1750 2575);
DISPLAY INVISIBLE (1750 2575);
FORCEADD Q_CAP..1
(1450 2375);
FORCEPROP 1 LAST PART_NUMBER CH4104K1B00
J 0
(1500 2175);
DISPLAY 0.787234 (1500 2175);
DISPLAY INVISIBLE (1500 2175);
FORCEPROP 1 LAST PACK_TYPE 0402
J 0
(1500 2225);
DISPLAY 0.787234 (1500 2225);
FORCEPROP 1 LAST TOLERANCE 10%
J 0
(1500 2325);
DISPLAY 0.787234 (1500 2325);
FORCEPROP 1 LAST VOLTAGE 25V
J 0
(1500 2375);
DISPLAY 0.787234 (1500 2375);
FORCEPROP 1 LAST MATERIAL X7R
J 0
(1500 2275);
DISPLAY 0.787234 (1500 2275);
FORCEPROP 1 LAST VALUE 0.1UF
J 0
(1500 2425);
DISPLAY 0.787234 (1500 2425);
FORCEPROP 1 LAST $LOCATION C1150
J 0
(1500 2475);
DISPLAY 0.978723 (1500 2475);
FORCEPROP 1 LASTPIN (1450 2475) $PN 1
J 0
(1460 2455);
DISPLAY 0.787234 (1460 2455);
FORCEPROP 1 LASTPIN (1450 2275) $PN 2
J 0
(1460 2255);
DISPLAY 0.787234 (1460 2255);
FORCEPROP 2 LAST CDS_LIB pure_quanta
J 0
(1450 2375);
PAINT MONO (1450 2375);
DISPLAY INVISIBLE (1450 2375);
FORCEPROP 1 LAST PATH I121
J 0
(1500 2525);
DISPLAY 0.978723 (1500 2525);
PAINT WHITE (1500 2525);
DISPLAY INVISIBLE (1500 2525);
FORCEPROP 2 LAST CDS_LOCATION C1150
J 0
(1500 2575);
DISPLAY 1.021277 (1500 2575);
DISPLAY INVISIBLE (1500 2575);
FORCEPROP 2 LAST $SEC 1
J 0
(1500 2575);
DISPLAY 0.680851 (1500 2575);
PAINT MONO (1500 2575);
DISPLAY INVISIBLE (1500 2575);
FORCEPROP 2 LAST CDS_SEC 1
J 0
(1500 2575);
DISPLAY 1.021277 (1500 2575);
DISPLAY INVISIBLE (1500 2575);
FORCEADD UNIVERSAL_GND..1
(1425 -200);
FORCEPROP 3 LASTPIN (1425 -150) SIG_NAME GND\g
J 0
(1435 -140);
DISPLAY 0.659574 (1435 -140);
PAINT MONO (1435 -140);
DISPLAY INVISIBLE (1435 -140);
FORCEPROP 2 LAST CDS_LIB logical_power
J 0
(1425 -200);
PAINT MONO (1425 -200);
DISPLAY INVISIBLE (1425 -200);
FORCEPROP 1 LAST HDL_POWER GND
J 1
(1450 -275);
DISPLAY 0.872340 (1450 -275);
PAINT GREEN (1450 -275);
DISPLAY INVISIBLE (1450 -275);
FORCEPROP 1 LAST PATH I13
J 0
(1500 -200);
DISPLAY 0.872340 (1500 -200);
PAINT AQUA (1500 -200);
DISPLAY INVISIBLE (1500 -200);
FORCEPROP 2 LAST ROOM IO_SLOT
J 1
(1200 -125);
DISPLAY 0.744681 (1200 -125);
DISPLAY INVISIBLE (1200 -125);
FORCEADD UNIVERSAL_POWER..1
(1450 -625);
FORCEPROP 3 LASTPIN (1450 -675) SIG_NAME P3V3_AUX_FPGA_VCCIO2\g
J 0
(1460 -665);
DISPLAY 0.659574 (1460 -665);
PAINT MONO (1460 -665);
DISPLAY INVISIBLE (1460 -665);
FORCEPROP 1 LAST HDL_POWER P3V3_AUX_FPGA_VCCIO2
J 1
(1450 -575);
DISPLAY 0.872340 (1450 -575);
PAINT GREEN (1450 -575);
FORCEPROP 2 LAST CDS_LIB logical_power
J 0
(1450 -625);
PAINT MONO (1450 -625);
DISPLAY INVISIBLE (1450 -625);
FORCEPROP 1 LAST PATH I14
J 0
(1500 -600);
DISPLAY 0.872340 (1500 -600);
PAINT AQUA (1500 -600);
DISPLAY INVISIBLE (1500 -600);
FORCEADD Q_CAP..1
(1450 -1000);
FORCEPROP 1 LAST PART_NUMBER CH31006KB18
J 0
(1500 -1150);
DISPLAY 0.978723 (1500 -1150);
DISPLAY INVISIBLE (1500 -1150);
FORCEPROP 1 LAST VALUE 0.01UF
J 0
(1500 -950);
DISPLAY 0.787234 (1500 -950);
FORCEPROP 1 LAST VOLTAGE 50V
J 0
(1500 -1000);
DISPLAY 0.787234 (1500 -1000);
FORCEPROP 1 LAST PACK_TYPE C0402
J 0
(1500 -1175);
DISPLAY 0.787234 (1500 -1175);
FORCEPROP 1 LAST MATERIAL X7R
J 0
(1500 -1100);
DISPLAY 0.787234 (1500 -1100);
FORCEPROP 1 LAST TOLERANCE 10%
J 0
(1500 -1050);
DISPLAY 0.787234 (1500 -1050);
FORCEPROP 1 LAST $LOCATION C1146
J 0
(1500 -900);
DISPLAY 0.787234 (1500 -900);
FORCEPROP 1 LASTPIN (1450 -900) $PN 1
J 0
(1460 -920);
DISPLAY 0.638298 (1460 -920);
PAINT MONO (1460 -920);
FORCEPROP 1 LASTPIN (1450 -1100) $PN 2
J 0
(1460 -1120);
DISPLAY 0.638298 (1460 -1120);
PAINT MONO (1460 -1120);
FORCEPROP 2 LAST CDS_LIB pure_quanta
J 0
(1450 -1000);
DISPLAY INVISIBLE (1450 -1000);
FORCEPROP 1 LAST PATH I15
J 0
(1500 -850);
DISPLAY 0.978723 (1500 -850);
PAINT WHITE (1500 -850);
DISPLAY INVISIBLE (1500 -850);
FORCEPROP 2 LAST CDS_LOCATION C1146
J 0
(1500 -800);
DISPLAY 1.021277 (1500 -800);
DISPLAY INVISIBLE (1500 -800);
FORCEPROP 0 LAST $SEC 1
J 0
(1500 -850);
DISPLAY 0.680851 (1500 -850);
PAINT MONO (1500 -850);
DISPLAY INVISIBLE (1500 -850);
FORCEPROP 2 LAST CDS_SEC 1
J 0
(1500 -800);
DISPLAY 1.021277 (1500 -800);
DISPLAY INVISIBLE (1500 -800);
FORCEADD UNIVERSAL_GND..1
(1450 -1325);
FORCEPROP 3 LASTPIN (1450 -1275) SIG_NAME GND\g
J 0
(1460 -1265);
DISPLAY 0.659574 (1460 -1265);
PAINT MONO (1460 -1265);
DISPLAY INVISIBLE (1460 -1265);
FORCEPROP 2 LAST CDS_LIB logical_power
J 0
(1450 -1325);
PAINT MONO (1450 -1325);
DISPLAY INVISIBLE (1450 -1325);
FORCEPROP 1 LAST HDL_POWER GND
J 1
(1475 -1400);
DISPLAY 0.872340 (1475 -1400);
PAINT GREEN (1475 -1400);
DISPLAY INVISIBLE (1475 -1400);
FORCEPROP 1 LAST PATH I16
J 0
(1525 -1325);
DISPLAY 0.872340 (1525 -1325);
PAINT AQUA (1525 -1325);
DISPLAY INVISIBLE (1525 -1325);
FORCEPROP 2 LAST ROOM IO_SLOT
J 1
(1225 -1250);
DISPLAY 0.744681 (1225 -1250);
DISPLAY INVISIBLE (1225 -1250);
FORCEADD UNIVERSAL_POWER..1
(1750 -1875);
FORCEPROP 3 LASTPIN (1750 -1925) SIG_NAME P3V3_AUX_FPGA_VCCIO5\g
J 0
(1760 -1915);
DISPLAY 0.659574 (1760 -1915);
PAINT MONO (1760 -1915);
DISPLAY INVISIBLE (1760 -1915);
FORCEPROP 1 LAST HDL_POWER P3V3_AUX_FPGA_VCCIO5
J 1
(1750 -1825);
DISPLAY 0.872340 (1750 -1825);
PAINT GREEN (1750 -1825);
FORCEPROP 2 LAST CDS_LIB logical_power
J 0
(1750 -1875);
PAINT MONO (1750 -1875);
DISPLAY INVISIBLE (1750 -1875);
FORCEPROP 1 LAST PATH I17
J 0
(1800 -1850);
DISPLAY 0.872340 (1800 -1850);
PAINT AQUA (1800 -1850);
DISPLAY INVISIBLE (1800 -1850);
FORCEADD Q_CAP..1
(1750 -2225);
FORCEPROP 1 LAST PART_NUMBER CH31006KB18
J 0
(1800 -2375);
DISPLAY 0.510638 (1800 -2375);
DISPLAY INVISIBLE (1800 -2375);
FORCEPROP 1 LAST TOLERANCE 10%
J 0
(1800 -2275);
DISPLAY 0.638298 (1800 -2275);
FORCEPROP 1 LAST VALUE 0.01UF
J 0
(1800 -2175);
DISPLAY 0.638298 (1800 -2175);
FORCEPROP 1 LAST VOLTAGE 50V
J 0
(1800 -2225);
DISPLAY 0.638298 (1800 -2225);
FORCEPROP 1 LAST PACK_TYPE C0402
J 0
(1800 -2425);
DISPLAY 0.638298 (1800 -2425);
FORCEPROP 1 LAST MATERIAL X7R
J 0
(1800 -2325);
DISPLAY 0.638298 (1800 -2325);
FORCEPROP 1 LAST $LOCATION C1904
J 0
(1800 -2125);
DISPLAY 0.638298 (1800 -2125);
FORCEPROP 1 LASTPIN (1750 -2125) $PN 1
J 0
(1760 -2145);
DISPLAY 0.787234 (1760 -2145);
PAINT MONO (1760 -2145);
FORCEPROP 1 LASTPIN (1750 -2325) $PN 2
J 0
(1760 -2345);
DISPLAY 0.787234 (1760 -2345);
PAINT MONO (1760 -2345);
FORCEPROP 2 LAST CDS_LIB pure_quanta
J 0
(1750 -2225);
DISPLAY INVISIBLE (1750 -2225);
FORCEPROP 1 LAST PATH I18
J 0
(1800 -2075);
DISPLAY 0.978723 (1800 -2075);
PAINT WHITE (1800 -2075);
DISPLAY INVISIBLE (1800 -2075);
FORCEPROP 2 LAST CDS_LOCATION C1904
J 0
(1800 -2025);
DISPLAY 1.021277 (1800 -2025);
DISPLAY INVISIBLE (1800 -2025);
FORCEPROP 0 LAST $SEC 1
J 0
(1800 -2075);
DISPLAY 0.680851 (1800 -2075);
PAINT MONO (1800 -2075);
DISPLAY INVISIBLE (1800 -2075);
FORCEPROP 2 LAST CDS_SEC 1
J 0
(1800 -2025);
DISPLAY 1.021277 (1800 -2025);
DISPLAY INVISIBLE (1800 -2025);
FORCEADD UNIVERSAL_GND..1
(1750 -2550);
FORCEPROP 3 LASTPIN (1750 -2500) SIG_NAME GND\g
J 0
(1760 -2490);
DISPLAY 0.659574 (1760 -2490);
PAINT MONO (1760 -2490);
DISPLAY INVISIBLE (1760 -2490);
FORCEPROP 2 LAST CDS_LIB logical_power
J 0
(1750 -2550);
DISPLAY INVISIBLE (1750 -2550);
FORCEPROP 1 LAST HDL_POWER GND
J 1
(1775 -2625);
DISPLAY 0.872340 (1775 -2625);
PAINT GREEN (1775 -2625);
DISPLAY INVISIBLE (1775 -2625);
FORCEPROP 1 LAST PATH I19
J 0
(1825 -2550);
DISPLAY 0.872340 (1825 -2550);
PAINT AQUA (1825 -2550);
DISPLAY INVISIBLE (1825 -2550);
FORCEPROP 2 LAST ROOM IO_SLOT
J 1
(1525 -2475);
DISPLAY 0.744681 (1525 -2475);
DISPLAY INVISIBLE (1525 -2475);
FORCEADD UNIVERSAL_POWER..1
(2200 2675);
FORCEPROP 3 LASTPIN (2200 2625) SIG_NAME VCC_PLD_CORE\g
J 0
(2210 2635);
DISPLAY 0.659574 (2210 2635);
PAINT MONO (2210 2635);
DISPLAY INVISIBLE (2210 2635);
FORCEPROP 1 LAST HDL_POWER VCC_PLD_CORE
J 1
(2200 2725);
DISPLAY 0.872340 (2200 2725);
PAINT GREEN (2200 2725);
FORCEPROP 2 LAST CDS_LIB logical_power
J 0
(2200 2675);
PAINT MONO (2200 2675);
DISPLAY INVISIBLE (2200 2675);
FORCEPROP 1 LAST PATH I2
J 0
(2250 2700);
DISPLAY 0.872340 (2250 2700);
PAINT AQUA (2250 2700);
DISPLAY INVISIBLE (2250 2700);
FORCEADD Q_CAP..1
(1500 -2225);
FORCEPROP 1 LAST PART_NUMBER CH31006KB18
J 0
(1550 -2375);
DISPLAY 0.404255 (1550 -2375);
DISPLAY INVISIBLE (1550 -2375);
FORCEPROP 1 LAST MATERIAL X7R
J 0
(1550 -2325);
DISPLAY 0.638298 (1550 -2325);
FORCEPROP 1 LAST TOLERANCE 10%
J 0
(1550 -2275);
DISPLAY 0.638298 (1550 -2275);
FORCEPROP 1 LAST VOLTAGE 50V
J 0
(1550 -2225);
DISPLAY 0.638298 (1550 -2225);
FORCEPROP 1 LAST VALUE 0.01UF
J 0
(1550 -2175);
DISPLAY 0.638298 (1550 -2175);
FORCEPROP 1 LAST PACK_TYPE C0402
J 0
(1550 -2425);
DISPLAY 0.638298 (1550 -2425);
FORCEPROP 1 LAST $LOCATION C1898
J 0
(1550 -2125);
DISPLAY 0.638298 (1550 -2125);
FORCEPROP 1 LASTPIN (1500 -2125) $PN 1
J 0
(1510 -2145);
DISPLAY 0.787234 (1510 -2145);
PAINT MONO (1510 -2145);
FORCEPROP 1 LASTPIN (1500 -2325) $PN 2
J 0
(1510 -2345);
DISPLAY 0.787234 (1510 -2345);
PAINT MONO (1510 -2345);
FORCEPROP 2 LAST CDS_LIB pure_quanta
J 0
(1500 -2225);
DISPLAY INVISIBLE (1500 -2225);
FORCEPROP 1 LAST PATH I20
J 0
(1550 -2075);
DISPLAY 0.978723 (1550 -2075);
PAINT WHITE (1550 -2075);
DISPLAY INVISIBLE (1550 -2075);
FORCEPROP 2 LAST CDS_LOCATION C1898
J 0
(1550 -2025);
DISPLAY 1.021277 (1550 -2025);
DISPLAY INVISIBLE (1550 -2025);
FORCEPROP 0 LAST $SEC 1
J 0
(1550 -2075);
DISPLAY 0.680851 (1550 -2075);
PAINT MONO (1550 -2075);
DISPLAY INVISIBLE (1550 -2075);
FORCEPROP 2 LAST CDS_SEC 1
J 0
(1550 -2025);
DISPLAY 1.021277 (1550 -2025);
DISPLAY INVISIBLE (1550 -2025);
FORCEADD Q_CAP..1
(1200 2375);
FORCEPROP 1 LAST PART_NUMBER CH31006KB18
J 0
(1250 2225);
DISPLAY 0.978723 (1250 2225);
DISPLAY INVISIBLE (1250 2225);
FORCEPROP 1 LAST PACK_TYPE C0402
J 0
(1250 2225);
DISPLAY 0.978723 (1250 2225);
FORCEPROP 1 LAST VOLTAGE 50V
J 0
(1250 2375);
DISPLAY 0.978723 (1250 2375);
FORCEPROP 1 LAST MATERIAL X7R
J 0
(1250 2275);
DISPLAY 0.978723 (1250 2275);
FORCEPROP 1 LAST TOLERANCE 10%
J 0
(1250 2325);
DISPLAY 0.978723 (1250 2325);
FORCEPROP 1 LAST VALUE 0.01UF
J 0
(1250 2425);
DISPLAY 0.978723 (1250 2425);
FORCEPROP 1 LAST $LOCATION C1931
J 0
(1250 2475);
DISPLAY 0.978723 (1250 2475);
FORCEPROP 1 LASTPIN (1200 2475) $PN 1
J 0
(1210 2455);
DISPLAY 0.787234 (1210 2455);
PAINT MONO (1210 2455);
FORCEPROP 1 LASTPIN (1200 2275) $PN 2
J 0
(1210 2255);
DISPLAY 0.787234 (1210 2255);
PAINT MONO (1210 2255);
FORCEPROP 2 LAST CDS_LIB pure_quanta
J 0
(1200 2375);
DISPLAY INVISIBLE (1200 2375);
FORCEPROP 1 LAST PATH I21
J 0
(1250 2525);
DISPLAY 0.978723 (1250 2525);
PAINT WHITE (1250 2525);
DISPLAY INVISIBLE (1250 2525);
FORCEPROP 2 LAST CDS_LOCATION C1931
J 0
(1250 2575);
DISPLAY 1.021277 (1250 2575);
DISPLAY INVISIBLE (1250 2575);
FORCEPROP 0 LAST $SEC 1
J 0
(1250 2525);
DISPLAY 0.680851 (1250 2525);
PAINT MONO (1250 2525);
DISPLAY INVISIBLE (1250 2525);
FORCEPROP 2 LAST CDS_SEC 1
J 0
(1250 2575);
DISPLAY 1.021277 (1250 2575);
DISPLAY INVISIBLE (1250 2575);
FORCEADD Q_CAP..1
(950 2375);
FORCEPROP 1 LAST PART_NUMBER CH31006KB18
J 0
(1000 2225);
DISPLAY 0.978723 (1000 2225);
DISPLAY INVISIBLE (1000 2225);
FORCEPROP 1 LAST MATERIAL X7R
J 0
(1000 2275);
DISPLAY 0.978723 (1000 2275);
FORCEPROP 1 LAST PACK_TYPE C0402
J 0
(1000 2225);
DISPLAY 0.978723 (1000 2225);
FORCEPROP 1 LAST TOLERANCE 10%
J 0
(1000 2325);
DISPLAY 0.978723 (1000 2325);
FORCEPROP 1 LAST VOLTAGE 50V
J 0
(1000 2375);
DISPLAY 0.978723 (1000 2375);
FORCEPROP 1 LAST VALUE 0.01UF
J 0
(1000 2425);
DISPLAY 0.978723 (1000 2425);
FORCEPROP 1 LAST $LOCATION C1928
J 0
(1000 2475);
DISPLAY 0.978723 (1000 2475);
FORCEPROP 1 LASTPIN (950 2475) $PN 1
J 0
(960 2455);
DISPLAY 0.787234 (960 2455);
PAINT MONO (960 2455);
FORCEPROP 1 LASTPIN (950 2275) $PN 2
J 0
(960 2255);
DISPLAY 0.787234 (960 2255);
PAINT MONO (960 2255);
FORCEPROP 2 LAST CDS_LIB pure_quanta
J 0
(950 2375);
DISPLAY INVISIBLE (950 2375);
FORCEPROP 1 LAST PATH I22
J 0
(1000 2525);
DISPLAY 0.978723 (1000 2525);
PAINT WHITE (1000 2525);
DISPLAY INVISIBLE (1000 2525);
FORCEPROP 2 LAST CDS_LOCATION C1928
J 0
(1000 2575);
DISPLAY 1.021277 (1000 2575);
DISPLAY INVISIBLE (1000 2575);
FORCEPROP 0 LAST $SEC 1
J 0
(1000 2525);
DISPLAY 0.680851 (1000 2525);
PAINT MONO (1000 2525);
DISPLAY INVISIBLE (1000 2525);
FORCEPROP 2 LAST CDS_SEC 1
J 0
(1000 2575);
DISPLAY 1.021277 (1000 2575);
DISPLAY INVISIBLE (1000 2575);
FORCEADD Q_CAP..1
(700 2375);
FORCEPROP 1 LAST PART_NUMBER CH31006KB18
J 0
(750 2225);
DISPLAY 0.978723 (750 2225);
DISPLAY INVISIBLE (750 2225);
FORCEPROP 1 LAST VOLTAGE 50V
J 0
(750 2375);
DISPLAY 0.978723 (750 2375);
FORCEPROP 1 LAST TOLERANCE 10%
J 0
(750 2325);
DISPLAY 0.978723 (750 2325);
FORCEPROP 1 LAST PACK_TYPE C0402
J 0
(750 2225);
DISPLAY 0.978723 (750 2225);
FORCEPROP 1 LAST MATERIAL X7R
J 0
(750 2275);
DISPLAY 0.978723 (750 2275);
FORCEPROP 1 LAST VALUE 0.01UF
J 0
(750 2425);
DISPLAY 0.978723 (750 2425);
FORCEPROP 1 LAST $LOCATION C1919
J 0
(750 2475);
DISPLAY 0.978723 (750 2475);
FORCEPROP 1 LASTPIN (700 2475) $PN 1
J 0
(710 2455);
DISPLAY 0.787234 (710 2455);
PAINT MONO (710 2455);
FORCEPROP 1 LASTPIN (700 2275) $PN 2
J 0
(710 2255);
DISPLAY 0.787234 (710 2255);
PAINT MONO (710 2255);
FORCEPROP 2 LAST CDS_LIB pure_quanta
J 0
(700 2375);
DISPLAY INVISIBLE (700 2375);
FORCEPROP 1 LAST PATH I23
J 0
(750 2525);
DISPLAY 0.978723 (750 2525);
PAINT WHITE (750 2525);
DISPLAY INVISIBLE (750 2525);
FORCEPROP 2 LAST CDS_LOCATION C1919
J 0
(750 2575);
DISPLAY 1.021277 (750 2575);
DISPLAY INVISIBLE (750 2575);
FORCEPROP 0 LAST $SEC 1
J 0
(750 2525);
DISPLAY 0.680851 (750 2525);
PAINT MONO (750 2525);
DISPLAY INVISIBLE (750 2525);
FORCEPROP 2 LAST CDS_SEC 1
J 0
(750 2575);
DISPLAY 1.021277 (750 2575);
DISPLAY INVISIBLE (750 2575);
FORCEADD Q_CAP..1
(450 2375);
FORCEPROP 1 LAST PART_NUMBER CH31006KB18
J 0
(500 2225);
DISPLAY 0.978723 (500 2225);
DISPLAY INVISIBLE (500 2225);
FORCEPROP 1 LAST VALUE 0.01UF
J 0
(500 2425);
DISPLAY 0.978723 (500 2425);
FORCEPROP 1 LAST PACK_TYPE C0402
J 0
(500 2225);
DISPLAY 0.978723 (500 2225);
FORCEPROP 1 LAST MATERIAL X7R
J 0
(500 2275);
DISPLAY 0.978723 (500 2275);
FORCEPROP 1 LAST TOLERANCE 10%
J 0
(500 2325);
DISPLAY 0.978723 (500 2325);
FORCEPROP 1 LAST VOLTAGE 50V
J 0
(500 2375);
DISPLAY 0.978723 (500 2375);
FORCEPROP 1 LAST $LOCATION C1916
J 0
(500 2475);
DISPLAY 0.978723 (500 2475);
FORCEPROP 1 LASTPIN (450 2475) $PN 1
J 0
(460 2455);
DISPLAY 0.787234 (460 2455);
PAINT MONO (460 2455);
FORCEPROP 1 LASTPIN (450 2275) $PN 2
J 0
(460 2255);
DISPLAY 0.787234 (460 2255);
PAINT MONO (460 2255);
FORCEPROP 2 LAST CDS_LIB pure_quanta
J 0
(450 2375);
DISPLAY INVISIBLE (450 2375);
FORCEPROP 1 LAST PATH I24
J 0
(500 2525);
DISPLAY 0.978723 (500 2525);
PAINT WHITE (500 2525);
DISPLAY INVISIBLE (500 2525);
FORCEPROP 2 LAST CDS_LOCATION C1916
J 0
(500 2575);
DISPLAY 1.021277 (500 2575);
DISPLAY INVISIBLE (500 2575);
FORCEPROP 0 LAST $SEC 1
J 0
(500 2525);
DISPLAY 0.680851 (500 2525);
PAINT MONO (500 2525);
DISPLAY INVISIBLE (500 2525);
FORCEPROP 2 LAST CDS_SEC 1
J 0
(500 2575);
DISPLAY 1.021277 (500 2575);
DISPLAY INVISIBLE (500 2575);
FORCEADD Q_CAP..1
(200 2375);
FORCEPROP 1 LAST PART_NUMBER CH4104K1B00
J 0
(250 2175);
DISPLAY 0.787234 (250 2175);
DISPLAY INVISIBLE (250 2175);
FORCEPROP 1 LAST PACK_TYPE 0402
J 0
(250 2225);
DISPLAY 0.787234 (250 2225);
FORCEPROP 1 LAST MATERIAL X7R
J 0
(250 2275);
DISPLAY 0.787234 (250 2275);
FORCEPROP 1 LAST VOLTAGE 25V
J 0
(250 2375);
DISPLAY 0.787234 (250 2375);
FORCEPROP 1 LAST TOLERANCE 10%
J 0
(250 2325);
DISPLAY 0.787234 (250 2325);
FORCEPROP 1 LAST VALUE 0.1UF
J 0
(250 2425);
DISPLAY 0.787234 (250 2425);
FORCEPROP 1 LAST $LOCATION C1907
J 0
(250 2475);
DISPLAY 0.978723 (250 2475);
FORCEPROP 1 LASTPIN (200 2475) $PN 1
J 0
(210 2455);
DISPLAY 0.787234 (210 2455);
FORCEPROP 1 LASTPIN (200 2275) $PN 2
J 0
(210 2255);
DISPLAY 0.787234 (210 2255);
FORCEPROP 2 LAST CDS_LIB pure_quanta
J 0
(200 2375);
PAINT MONO (200 2375);
DISPLAY INVISIBLE (200 2375);
FORCEPROP 1 LAST PATH I25
J 0
(250 2525);
DISPLAY 0.978723 (250 2525);
PAINT WHITE (250 2525);
DISPLAY INVISIBLE (250 2525);
FORCEPROP 2 LAST CDS_LOCATION C1907
J 0
(250 2575);
DISPLAY 1.021277 (250 2575);
DISPLAY INVISIBLE (250 2575);
FORCEPROP 2 LAST $SEC 1
J 0
(250 2575);
DISPLAY 0.680851 (250 2575);
PAINT MONO (250 2575);
DISPLAY INVISIBLE (250 2575);
FORCEPROP 2 LAST CDS_SEC 1
J 0
(250 2575);
DISPLAY 1.021277 (250 2575);
DISPLAY INVISIBLE (250 2575);
FORCEADD Q_CAP..1
(-50 2375);
FORCEPROP 1 LAST PART_NUMBER CH31006KB18
J 0
(0 2225);
DISPLAY 0.978723 (0 2225);
DISPLAY INVISIBLE (0 2225);
FORCEPROP 1 LAST TOLERANCE 10%
J 0
(0 2325);
DISPLAY 0.978723 (0 2325);
FORCEPROP 1 LAST MATERIAL X7R
J 0
(0 2275);
DISPLAY 0.978723 (0 2275);
FORCEPROP 1 LAST VOLTAGE 50V
J 0
(0 2375);
DISPLAY 0.978723 (0 2375);
FORCEPROP 1 LAST VALUE 0.01UF
J 0
(0 2425);
DISPLAY 0.978723 (0 2425);
FORCEPROP 1 LAST PACK_TYPE C0402
J 0
(0 2225);
DISPLAY 0.978723 (0 2225);
FORCEPROP 1 LAST $LOCATION C1903
J 0
(0 2475);
DISPLAY 0.978723 (0 2475);
FORCEPROP 1 LASTPIN (-50 2475) $PN 1
J 0
(-40 2455);
DISPLAY 0.787234 (-40 2455);
PAINT MONO (-40 2455);
FORCEPROP 1 LASTPIN (-50 2275) $PN 2
J 0
(-40 2255);
DISPLAY 0.787234 (-40 2255);
PAINT MONO (-40 2255);
FORCEPROP 2 LAST CDS_LIB pure_quanta
J 0
(-50 2375);
DISPLAY INVISIBLE (-50 2375);
FORCEPROP 1 LAST PATH I26
J 0
(0 2525);
DISPLAY 0.978723 (0 2525);
PAINT WHITE (0 2525);
DISPLAY INVISIBLE (0 2525);
FORCEPROP 2 LAST CDS_LOCATION C1903
J 0
(0 2575);
DISPLAY 1.021277 (0 2575);
DISPLAY INVISIBLE (0 2575);
FORCEPROP 0 LAST $SEC 1
J 0
(0 2525);
DISPLAY 0.680851 (0 2525);
PAINT MONO (0 2525);
DISPLAY INVISIBLE (0 2525);
FORCEPROP 2 LAST CDS_SEC 1
J 0
(0 2575);
DISPLAY 1.021277 (0 2575);
DISPLAY INVISIBLE (0 2575);
FORCEADD Q_CAP..1
(-300 2375);
FORCEPROP 1 LAST PART_NUMBER CH31006KB18
J 0
(-250 2225);
DISPLAY 0.978723 (-250 2225);
DISPLAY INVISIBLE (-250 2225);
FORCEPROP 1 LAST PACK_TYPE C0402
J 0
(-250 2225);
DISPLAY 0.978723 (-250 2225);
FORCEPROP 1 LAST MATERIAL X7R
J 0
(-250 2275);
DISPLAY 0.978723 (-250 2275);
FORCEPROP 1 LAST VOLTAGE 50V
J 0
(-250 2375);
DISPLAY 0.978723 (-250 2375);
FORCEPROP 1 LAST VALUE 0.01UF
J 0
(-250 2425);
DISPLAY 0.978723 (-250 2425);
FORCEPROP 1 LAST TOLERANCE 10%
J 0
(-250 2325);
DISPLAY 0.978723 (-250 2325);
FORCEPROP 1 LAST $LOCATION C1897
J 0
(-250 2475);
DISPLAY 0.978723 (-250 2475);
FORCEPROP 1 LASTPIN (-300 2475) $PN 1
J 0
(-290 2455);
DISPLAY 0.787234 (-290 2455);
PAINT MONO (-290 2455);
FORCEPROP 1 LASTPIN (-300 2275) $PN 2
J 0
(-290 2255);
DISPLAY 0.787234 (-290 2255);
PAINT MONO (-290 2255);
FORCEPROP 2 LAST CDS_LIB pure_quanta
J 0
(-300 2375);
DISPLAY INVISIBLE (-300 2375);
FORCEPROP 1 LAST PATH I27
J 0
(-250 2525);
DISPLAY 0.978723 (-250 2525);
PAINT WHITE (-250 2525);
DISPLAY INVISIBLE (-250 2525);
FORCEPROP 2 LAST CDS_LOCATION C1897
J 0
(-250 2575);
DISPLAY 1.021277 (-250 2575);
DISPLAY INVISIBLE (-250 2575);
FORCEPROP 0 LAST $SEC 1
J 0
(-250 2525);
DISPLAY 0.680851 (-250 2525);
PAINT MONO (-250 2525);
DISPLAY INVISIBLE (-250 2525);
FORCEPROP 2 LAST CDS_SEC 1
J 0
(-250 2575);
DISPLAY 1.021277 (-250 2575);
DISPLAY INVISIBLE (-250 2575);
FORCEADD Q_CAP..1
(-575 2400);
FORCEPROP 1 LAST PART_NUMBER CH31006KB18
J 0
(-525 2250);
DISPLAY 0.978723 (-525 2250);
DISPLAY INVISIBLE (-525 2250);
FORCEPROP 1 LAST PACK_TYPE C0402
J 0
(-525 2250);
DISPLAY 0.978723 (-525 2250);
FORCEPROP 1 LAST MATERIAL X7R
J 0
(-525 2300);
DISPLAY 0.978723 (-525 2300);
FORCEPROP 1 LAST TOLERANCE 10%
J 0
(-525 2350);
DISPLAY 0.978723 (-525 2350);
FORCEPROP 1 LAST VOLTAGE 50V
J 0
(-525 2400);
DISPLAY 0.978723 (-525 2400);
FORCEPROP 1 LAST VALUE 0.01UF
J 0
(-525 2450);
DISPLAY 0.978723 (-525 2450);
FORCEPROP 1 LAST $LOCATION C1912
J 0
(-525 2500);
DISPLAY 0.978723 (-525 2500);
FORCEPROP 1 LASTPIN (-575 2500) $PN 1
J 0
(-565 2480);
DISPLAY 0.787234 (-565 2480);
PAINT MONO (-565 2480);
FORCEPROP 1 LASTPIN (-575 2300) $PN 2
J 0
(-565 2280);
DISPLAY 0.787234 (-565 2280);
PAINT MONO (-565 2280);
FORCEPROP 2 LAST CDS_LIB pure_quanta
J 0
(-575 2400);
DISPLAY INVISIBLE (-575 2400);
FORCEPROP 1 LAST PATH I28
J 0
(-525 2550);
DISPLAY 0.978723 (-525 2550);
PAINT WHITE (-525 2550);
DISPLAY INVISIBLE (-525 2550);
FORCEPROP 2 LAST CDS_LOCATION C1912
J 0
(-525 2600);
DISPLAY 1.021277 (-525 2600);
DISPLAY INVISIBLE (-525 2600);
FORCEPROP 0 LAST $SEC 1
J 0
(-525 2550);
DISPLAY 0.680851 (-525 2550);
PAINT MONO (-525 2550);
DISPLAY INVISIBLE (-525 2550);
FORCEPROP 2 LAST CDS_SEC 1
J 0
(-525 2600);
DISPLAY 1.021277 (-525 2600);
DISPLAY INVISIBLE (-525 2600);
FORCEADD Q_CAP..1
(-925 2400);
FORCEPROP 1 LAST PART_NUMBER CH4104K1B00
J 0
(-875 2200);
DISPLAY 0.787234 (-875 2200);
DISPLAY INVISIBLE (-875 2200);
FORCEPROP 1 LAST PACK_TYPE 0402
J 0
(-875 2250);
DISPLAY 0.787234 (-875 2250);
FORCEPROP 1 LAST VALUE 0.1UF
J 0
(-875 2450);
DISPLAY 0.787234 (-875 2450);
FORCEPROP 1 LAST VOLTAGE 25V
J 0
(-875 2400);
DISPLAY 0.787234 (-875 2400);
FORCEPROP 1 LAST TOLERANCE 10%
J 0
(-875 2350);
DISPLAY 0.787234 (-875 2350);
FORCEPROP 1 LAST MATERIAL X7R
J 0
(-875 2300);
DISPLAY 0.787234 (-875 2300);
FORCEPROP 1 LAST $LOCATION C1943
J 0
(-875 2500);
DISPLAY 0.978723 (-875 2500);
FORCEPROP 1 LASTPIN (-925 2500) $PN 1
J 0
(-915 2480);
DISPLAY 0.787234 (-915 2480);
PAINT MONO (-915 2480);
FORCEPROP 1 LASTPIN (-925 2300) $PN 2
J 0
(-915 2280);
DISPLAY 0.787234 (-915 2280);
PAINT MONO (-915 2280);
FORCEPROP 2 LAST CDS_LIB pure_quanta
J 0
(-925 2400);
DISPLAY INVISIBLE (-925 2400);
FORCEPROP 1 LAST PATH I29
J 0
(-875 2550);
DISPLAY 0.978723 (-875 2550);
PAINT WHITE (-875 2550);
DISPLAY INVISIBLE (-875 2550);
FORCEPROP 0 LAST CDS_LOCATION C1943
J 0
(-875 2550);
DISPLAY 1.021277 (-875 2550);
DISPLAY INVISIBLE (-875 2550);
FORCEPROP 0 LAST $SEC 1
J 0
(-875 2550);
DISPLAY 0.680851 (-875 2550);
PAINT MONO (-875 2550);
DISPLAY INVISIBLE (-875 2550);
FORCEPROP 0 LAST CDS_SEC 1
J 0
(-875 2550);
DISPLAY 1.021277 (-875 2550);
DISPLAY INVISIBLE (-875 2550);
FORCEADD Q_CAP..1
(2200 2375);
FORCEPROP 1 LAST PART_NUMBER CH31006KB18
J 0
(2250 2225);
DISPLAY 0.978723 (2250 2225);
DISPLAY INVISIBLE (2250 2225);
FORCEPROP 1 LAST PACK_TYPE C0402
J 0
(2250 2225);
DISPLAY 0.978723 (2250 2225);
FORCEPROP 1 LAST VOLTAGE 50V
J 0
(2250 2375);
DISPLAY 0.978723 (2250 2375);
FORCEPROP 1 LAST TOLERANCE 10%
J 0
(2250 2325);
DISPLAY 0.978723 (2250 2325);
FORCEPROP 1 LAST MATERIAL X7R
J 0
(2250 2275);
DISPLAY 0.978723 (2250 2275);
FORCEPROP 1 LAST VALUE 0.01UF
J 0
(2250 2425);
DISPLAY 0.978723 (2250 2425);
FORCEPROP 1 LAST $LOCATION C1154
J 0
(2250 2475);
DISPLAY 0.978723 (2250 2475);
FORCEPROP 1 LASTPIN (2200 2475) $PN 1
J 0
(2210 2455);
DISPLAY 0.787234 (2210 2455);
PAINT MONO (2210 2455);
FORCEPROP 1 LASTPIN (2200 2275) $PN 2
J 0
(2210 2255);
DISPLAY 0.787234 (2210 2255);
PAINT MONO (2210 2255);
FORCEPROP 2 LAST CDS_LIB pure_quanta
J 0
(2200 2375);
DISPLAY INVISIBLE (2200 2375);
FORCEPROP 1 LAST PATH I3
J 0
(2250 2525);
DISPLAY 0.978723 (2250 2525);
PAINT WHITE (2250 2525);
DISPLAY INVISIBLE (2250 2525);
FORCEPROP 2 LAST CDS_LOCATION C1154
J 0
(2250 2575);
DISPLAY 1.021277 (2250 2575);
DISPLAY INVISIBLE (2250 2575);
FORCEPROP 0 LAST $SEC 1
J 0
(2250 2525);
DISPLAY 0.680851 (2250 2525);
PAINT MONO (2250 2525);
DISPLAY INVISIBLE (2250 2525);
FORCEPROP 2 LAST CDS_SEC 1
J 0
(2250 2575);
DISPLAY 1.021277 (2250 2575);
DISPLAY INVISIBLE (2250 2575);
FORCEADD Q_CAP..1
(-1275 2400);
FORCEPROP 1 LAST PART_NUMBER CH6101MEB01
J 0
(-1225 2250);
DISPLAY 0.638298 (-1225 2250);
DISPLAY INVISIBLE (-1225 2250);
FORCEPROP 1 LAST MATERIAL X6S
J 0
(-1225 2300);
DISPLAY 0.638298 (-1225 2300);
FORCEPROP 1 LAST TOLERANCE 20%
J 0
(-1225 2350);
DISPLAY 0.638298 (-1225 2350);
FORCEPROP 1 LAST VOLTAGE 6.3V
J 0
(-1225 2400);
DISPLAY 0.638298 (-1225 2400);
FORCEPROP 1 LAST VALUE 10UF
J 0
(-1225 2450);
DISPLAY 0.638298 (-1225 2450);
FORCEPROP 1 LAST PACK_TYPE C0402
J 0
(-1225 2200);
DISPLAY 0.638298 (-1225 2200);
FORCEPROP 1 LAST $LOCATION C1936
J 0
(-1225 2500);
DISPLAY 0.978723 (-1225 2500);
FORCEPROP 1 LASTPIN (-1275 2500) $PN 1
J 0
(-1265 2480);
DISPLAY 0.787234 (-1265 2480);
PAINT MONO (-1265 2480);
FORCEPROP 1 LASTPIN (-1275 2300) $PN 2
J 0
(-1265 2280);
DISPLAY 0.787234 (-1265 2280);
PAINT MONO (-1265 2280);
FORCEPROP 2 LAST CDS_LIB pure_quanta
J 0
(-1275 2400);
DISPLAY INVISIBLE (-1275 2400);
FORCEPROP 1 LAST PATH I30
J 0
(-1225 2550);
DISPLAY 0.978723 (-1225 2550);
PAINT WHITE (-1225 2550);
DISPLAY INVISIBLE (-1225 2550);
FORCEPROP 0 LAST CDS_LOCATION C1936
J 0
(-1225 2550);
DISPLAY 1.021277 (-1225 2550);
DISPLAY INVISIBLE (-1225 2550);
FORCEPROP 0 LAST $SEC 1
J 0
(-1225 2550);
DISPLAY 0.680851 (-1225 2550);
PAINT MONO (-1225 2550);
DISPLAY INVISIBLE (-1225 2550);
FORCEPROP 0 LAST CDS_SEC 1
J 0
(-1225 2550);
DISPLAY 1.021277 (-1225 2550);
DISPLAY INVISIBLE (-1225 2550);
FORCEADD UNIVERSAL_POWER..1
(-2050 2875);
FORCEPROP 3 LASTPIN (-2050 2825) SIG_NAME P3V3_AUX\g
J 0
(-2040 2835);
DISPLAY 0.659574 (-2040 2835);
PAINT MONO (-2040 2835);
DISPLAY INVISIBLE (-2040 2835);
FORCEPROP 1 LAST HDL_POWER P3V3_AUX
J 1
(-2050 2925);
DISPLAY 0.872340 (-2050 2925);
PAINT GREEN (-2050 2925);
FORCEPROP 2 LAST CDS_LIB logical_power
J 0
(-2050 2875);
PAINT MONO (-2050 2875);
DISPLAY INVISIBLE (-2050 2875);
FORCEPROP 1 LAST PATH I32
J 0
(-2000 2900);
DISPLAY 0.872340 (-2000 2900);
PAINT AQUA (-2000 2900);
DISPLAY INVISIBLE (-2000 2900);
FORCEADD Q_CAP..1
(1250 1150);
FORCEPROP 1 LAST PART_NUMBER CH31006KB18
J 0
(1300 1000);
DISPLAY 0.978723 (1300 1000);
DISPLAY INVISIBLE (1300 1000);
FORCEPROP 1 LAST VALUE 0.01UF
J 0
(1300 1200);
DISPLAY 0.638298 (1300 1200);
FORCEPROP 1 LAST TOLERANCE 10%
J 0
(1300 1100);
DISPLAY 0.638298 (1300 1100);
FORCEPROP 1 LAST MATERIAL X7R
J 0
(1300 1050);
DISPLAY 0.638298 (1300 1050);
FORCEPROP 1 LAST VOLTAGE 50V
J 0
(1300 1150);
DISPLAY 0.638298 (1300 1150);
FORCEPROP 1 LAST PACK_TYPE C0402
J 0
(1300 1000);
DISPLAY 0.638298 (1300 1000);
FORCEPROP 1 LAST $LOCATION C1929
J 0
(1300 1250);
DISPLAY 0.638298 (1300 1250);
FORCEPROP 1 LASTPIN (1250 1250) $PN 1
J 0
(1260 1230);
DISPLAY 0.510638 (1260 1230);
PAINT MONO (1260 1230);
FORCEPROP 1 LASTPIN (1250 1050) $PN 2
J 0
(1260 1030);
DISPLAY 0.510638 (1260 1030);
PAINT MONO (1260 1030);
FORCEPROP 2 LAST CDS_LIB pure_quanta
J 0
(1250 1150);
DISPLAY INVISIBLE (1250 1150);
FORCEPROP 1 LAST PATH I33
J 0
(1300 1300);
DISPLAY 0.978723 (1300 1300);
PAINT WHITE (1300 1300);
DISPLAY INVISIBLE (1300 1300);
FORCEPROP 2 LAST CDS_LOCATION C1929
J 0
(1300 1350);
DISPLAY 1.021277 (1300 1350);
DISPLAY INVISIBLE (1300 1350);
FORCEPROP 0 LAST $SEC 1
J 0
(1300 1300);
DISPLAY 0.680851 (1300 1300);
PAINT MONO (1300 1300);
DISPLAY INVISIBLE (1300 1300);
FORCEPROP 2 LAST CDS_SEC 1
J 0
(1300 1350);
DISPLAY 1.021277 (1300 1350);
DISPLAY INVISIBLE (1300 1350);
FORCEADD Q_CAP..1
(1000 1150);
FORCEPROP 1 LAST PART_NUMBER CH31006KB18
J 0
(1050 1000);
DISPLAY 0.978723 (1050 1000);
DISPLAY INVISIBLE (1050 1000);
FORCEPROP 1 LAST VALUE 0.01UF
J 0
(1050 1200);
DISPLAY 0.638298 (1050 1200);
FORCEPROP 1 LAST TOLERANCE 10%
J 0
(1050 1100);
DISPLAY 0.638298 (1050 1100);
FORCEPROP 1 LAST MATERIAL X7R
J 0
(1050 1050);
DISPLAY 0.638298 (1050 1050);
FORCEPROP 1 LAST VOLTAGE 50V
J 0
(1050 1150);
DISPLAY 0.638298 (1050 1150);
FORCEPROP 1 LAST PACK_TYPE C0402
J 0
(1050 1000);
DISPLAY 0.638298 (1050 1000);
FORCEPROP 1 LAST $LOCATION C1926
J 0
(1050 1250);
DISPLAY 0.638298 (1050 1250);
FORCEPROP 1 LASTPIN (1000 1250) $PN 1
J 0
(1010 1230);
DISPLAY 0.510638 (1010 1230);
PAINT MONO (1010 1230);
FORCEPROP 1 LASTPIN (1000 1050) $PN 2
J 0
(1010 1030);
DISPLAY 0.510638 (1010 1030);
PAINT MONO (1010 1030);
FORCEPROP 2 LAST CDS_LIB pure_quanta
J 0
(1000 1150);
DISPLAY INVISIBLE (1000 1150);
FORCEPROP 1 LAST PATH I34
J 0
(1050 1300);
DISPLAY 0.978723 (1050 1300);
PAINT WHITE (1050 1300);
DISPLAY INVISIBLE (1050 1300);
FORCEPROP 2 LAST CDS_LOCATION C1926
J 0
(1050 1350);
DISPLAY 1.021277 (1050 1350);
DISPLAY INVISIBLE (1050 1350);
FORCEPROP 0 LAST $SEC 1
J 0
(1050 1300);
DISPLAY 0.680851 (1050 1300);
PAINT MONO (1050 1300);
DISPLAY INVISIBLE (1050 1300);
FORCEPROP 2 LAST CDS_SEC 1
J 0
(1050 1350);
DISPLAY 1.021277 (1050 1350);
DISPLAY INVISIBLE (1050 1350);
FORCEADD Q_CAP..1
(750 1150);
FORCEPROP 1 LAST PART_NUMBER CH31006KB18
J 0
(800 1000);
DISPLAY 0.978723 (800 1000);
DISPLAY INVISIBLE (800 1000);
FORCEPROP 1 LAST VOLTAGE 50V
J 0
(800 1150);
DISPLAY 0.638298 (800 1150);
FORCEPROP 1 LAST MATERIAL X7R
J 0
(800 1050);
DISPLAY 0.638298 (800 1050);
FORCEPROP 1 LAST TOLERANCE 10%
J 0
(800 1100);
DISPLAY 0.638298 (800 1100);
FORCEPROP 1 LAST PACK_TYPE C0402
J 0
(800 1000);
DISPLAY 0.638298 (800 1000);
FORCEPROP 1 LAST VALUE 0.01UF
J 0
(800 1200);
DISPLAY 0.638298 (800 1200);
FORCEPROP 1 LAST $LOCATION C1917
J 0
(800 1250);
DISPLAY 0.638298 (800 1250);
FORCEPROP 1 LASTPIN (750 1250) $PN 1
J 0
(760 1230);
DISPLAY 0.510638 (760 1230);
PAINT MONO (760 1230);
FORCEPROP 1 LASTPIN (750 1050) $PN 2
J 0
(760 1030);
DISPLAY 0.510638 (760 1030);
PAINT MONO (760 1030);
FORCEPROP 2 LAST CDS_LIB pure_quanta
J 0
(750 1150);
DISPLAY INVISIBLE (750 1150);
FORCEPROP 1 LAST PATH I35
J 0
(800 1300);
DISPLAY 0.978723 (800 1300);
PAINT WHITE (800 1300);
DISPLAY INVISIBLE (800 1300);
FORCEPROP 2 LAST CDS_LOCATION C1917
J 0
(800 1350);
DISPLAY 1.021277 (800 1350);
DISPLAY INVISIBLE (800 1350);
FORCEPROP 0 LAST $SEC 1
J 0
(800 1300);
DISPLAY 0.680851 (800 1300);
PAINT MONO (800 1300);
DISPLAY INVISIBLE (800 1300);
FORCEPROP 2 LAST CDS_SEC 1
J 0
(800 1350);
DISPLAY 1.021277 (800 1350);
DISPLAY INVISIBLE (800 1350);
FORCEADD Q_CAP..1
(500 1150);
FORCEPROP 1 LAST PART_NUMBER CH31006KB18
J 0
(550 1000);
DISPLAY 0.978723 (550 1000);
DISPLAY INVISIBLE (550 1000);
FORCEPROP 1 LAST VALUE 0.01UF
J 0
(550 1200);
DISPLAY 0.638298 (550 1200);
FORCEPROP 1 LAST VOLTAGE 50V
J 0
(550 1150);
DISPLAY 0.638298 (550 1150);
FORCEPROP 1 LAST TOLERANCE 10%
J 0
(550 1100);
DISPLAY 0.638298 (550 1100);
FORCEPROP 1 LAST MATERIAL X7R
J 0
(550 1050);
DISPLAY 0.638298 (550 1050);
FORCEPROP 1 LAST PACK_TYPE C0402
J 0
(550 1000);
DISPLAY 0.638298 (550 1000);
FORCEPROP 1 LAST $LOCATION C1914
J 0
(550 1250);
DISPLAY 0.638298 (550 1250);
FORCEPROP 1 LASTPIN (500 1250) $PN 1
J 0
(510 1230);
DISPLAY 0.787234 (510 1230);
PAINT MONO (510 1230);
FORCEPROP 1 LASTPIN (500 1050) $PN 2
J 0
(510 1030);
DISPLAY 0.787234 (510 1030);
PAINT MONO (510 1030);
FORCEPROP 2 LAST CDS_LIB pure_quanta
J 0
(500 1150);
DISPLAY INVISIBLE (500 1150);
FORCEPROP 1 LAST PATH I36
J 0
(550 1300);
DISPLAY 0.978723 (550 1300);
PAINT WHITE (550 1300);
DISPLAY INVISIBLE (550 1300);
FORCEPROP 2 LAST CDS_LOCATION C1914
J 0
(550 1350);
DISPLAY 1.021277 (550 1350);
DISPLAY INVISIBLE (550 1350);
FORCEPROP 0 LAST $SEC 1
J 0
(550 1300);
DISPLAY 0.680851 (550 1300);
PAINT MONO (550 1300);
DISPLAY INVISIBLE (550 1300);
FORCEPROP 2 LAST CDS_SEC 1
J 0
(550 1350);
DISPLAY 1.021277 (550 1350);
DISPLAY INVISIBLE (550 1350);
FORCEADD Q_CAP..1
(1175 125);
FORCEPROP 1 LAST PART_NUMBER CH31006KB18
J 0
(1225 -25);
DISPLAY 0.978723 (1225 -25);
DISPLAY INVISIBLE (1225 -25);
FORCEPROP 1 LAST MATERIAL X7R
J 0
(1225 25);
DISPLAY 0.787234 (1225 25);
FORCEPROP 1 LAST PACK_TYPE C0402
J 0
(1225 -25);
DISPLAY 0.787234 (1225 -25);
FORCEPROP 1 LAST VOLTAGE 50V
J 0
(1225 125);
DISPLAY 0.787234 (1225 125);
FORCEPROP 1 LAST TOLERANCE 10%
J 0
(1225 75);
DISPLAY 0.787234 (1225 75);
FORCEPROP 1 LAST VALUE 0.01UF
J 0
(1225 175);
DISPLAY 0.787234 (1225 175);
FORCEPROP 1 LAST $LOCATION C1930
J 0
(1225 225);
DISPLAY 0.787234 (1225 225);
FORCEPROP 1 LASTPIN (1175 225) $PN 1
J 0
(1185 205);
DISPLAY 0.638298 (1185 205);
PAINT MONO (1185 205);
FORCEPROP 1 LASTPIN (1175 25) $PN 2
J 0
(1185 5);
DISPLAY 0.638298 (1185 5);
PAINT MONO (1185 5);
FORCEPROP 2 LAST CDS_LIB pure_quanta
J 0
(1175 125);
DISPLAY INVISIBLE (1175 125);
FORCEPROP 1 LAST PATH I37
J 0
(1225 275);
DISPLAY 0.978723 (1225 275);
PAINT WHITE (1225 275);
DISPLAY INVISIBLE (1225 275);
FORCEPROP 2 LAST CDS_LOCATION C1930
J 0
(1225 325);
DISPLAY 1.021277 (1225 325);
DISPLAY INVISIBLE (1225 325);
FORCEPROP 0 LAST $SEC 1
J 0
(1225 275);
DISPLAY 0.680851 (1225 275);
PAINT MONO (1225 275);
DISPLAY INVISIBLE (1225 275);
FORCEPROP 2 LAST CDS_SEC 1
J 0
(1225 325);
DISPLAY 1.021277 (1225 325);
DISPLAY INVISIBLE (1225 325);
FORCEADD Q_CAP..1
(925 125);
FORCEPROP 1 LAST PART_NUMBER CH31006KB18
J 0
(975 -25);
DISPLAY 0.978723 (975 -25);
DISPLAY INVISIBLE (975 -25);
FORCEPROP 1 LAST VOLTAGE 50V
J 0
(975 125);
DISPLAY 0.787234 (975 125);
FORCEPROP 1 LAST PACK_TYPE C0402
J 0
(975 -25);
DISPLAY 0.787234 (975 -25);
FORCEPROP 1 LAST MATERIAL X7R
J 0
(975 25);
DISPLAY 0.787234 (975 25);
FORCEPROP 1 LAST TOLERANCE 10%
J 0
(975 75);
DISPLAY 0.787234 (975 75);
FORCEPROP 1 LAST VALUE 0.01UF
J 0
(975 175);
DISPLAY 0.787234 (975 175);
FORCEPROP 1 LAST $LOCATION C1927
J 0
(975 225);
DISPLAY 0.787234 (975 225);
FORCEPROP 1 LASTPIN (925 225) $PN 1
J 0
(935 205);
DISPLAY 0.638298 (935 205);
PAINT MONO (935 205);
FORCEPROP 1 LASTPIN (925 25) $PN 2
J 0
(935 5);
DISPLAY 0.638298 (935 5);
PAINT MONO (935 5);
FORCEPROP 2 LAST CDS_LIB pure_quanta
J 0
(925 125);
DISPLAY INVISIBLE (925 125);
FORCEPROP 1 LAST PATH I38
J 0
(975 275);
DISPLAY 0.978723 (975 275);
PAINT WHITE (975 275);
DISPLAY INVISIBLE (975 275);
FORCEPROP 2 LAST CDS_LOCATION C1927
J 0
(975 325);
DISPLAY 1.021277 (975 325);
DISPLAY INVISIBLE (975 325);
FORCEPROP 0 LAST $SEC 1
J 0
(975 275);
DISPLAY 0.680851 (975 275);
PAINT MONO (975 275);
DISPLAY INVISIBLE (975 275);
FORCEPROP 2 LAST CDS_SEC 1
J 0
(975 325);
DISPLAY 1.021277 (975 325);
DISPLAY INVISIBLE (975 325);
FORCEADD Q_CAP..1
(675 125);
FORCEPROP 1 LAST PART_NUMBER CH31006KB18
J 0
(725 -25);
DISPLAY 0.978723 (725 -25);
DISPLAY INVISIBLE (725 -25);
FORCEPROP 1 LAST MATERIAL X7R
J 0
(725 25);
DISPLAY 0.787234 (725 25);
FORCEPROP 1 LAST VALUE 0.01UF
J 0
(725 175);
DISPLAY 0.787234 (725 175);
FORCEPROP 1 LAST PACK_TYPE C0402
J 0
(725 -25);
DISPLAY 0.787234 (725 -25);
FORCEPROP 1 LAST VOLTAGE 50V
J 0
(725 125);
DISPLAY 0.787234 (725 125);
FORCEPROP 1 LAST TOLERANCE 10%
J 0
(725 75);
DISPLAY 0.787234 (725 75);
FORCEPROP 1 LAST $LOCATION C1918
J 0
(725 225);
DISPLAY 0.787234 (725 225);
FORCEPROP 1 LASTPIN (675 225) $PN 1
J 0
(685 205);
DISPLAY 0.638298 (685 205);
PAINT MONO (685 205);
FORCEPROP 1 LASTPIN (675 25) $PN 2
J 0
(685 5);
DISPLAY 0.638298 (685 5);
PAINT MONO (685 5);
FORCEPROP 2 LAST CDS_LIB pure_quanta
J 0
(675 125);
DISPLAY INVISIBLE (675 125);
FORCEPROP 1 LAST PATH I39
J 0
(725 275);
DISPLAY 0.978723 (725 275);
PAINT WHITE (725 275);
DISPLAY INVISIBLE (725 275);
FORCEPROP 2 LAST CDS_LOCATION C1918
J 0
(725 325);
DISPLAY 1.021277 (725 325);
DISPLAY INVISIBLE (725 325);
FORCEPROP 0 LAST $SEC 1
J 0
(725 275);
DISPLAY 0.680851 (725 275);
PAINT MONO (725 275);
DISPLAY INVISIBLE (725 275);
FORCEPROP 2 LAST CDS_SEC 1
J 0
(725 325);
DISPLAY 1.021277 (725 325);
DISPLAY INVISIBLE (725 325);
FORCEADD UNIVERSAL_GND..1
(2200 2025);
FORCEPROP 3 LASTPIN (2200 2075) SIG_NAME GND\g
J 0
(2210 2085);
DISPLAY 0.659574 (2210 2085);
PAINT MONO (2210 2085);
DISPLAY INVISIBLE (2210 2085);
FORCEPROP 2 LAST CDS_LIB logical_power
J 0
(2200 2025);
PAINT MONO (2200 2025);
DISPLAY INVISIBLE (2200 2025);
FORCEPROP 1 LAST HDL_POWER GND
J 1
(2225 1950);
DISPLAY 0.872340 (2225 1950);
PAINT GREEN (2225 1950);
DISPLAY INVISIBLE (2225 1950);
FORCEPROP 1 LAST PATH I4
J 0
(2275 2025);
DISPLAY 0.872340 (2275 2025);
PAINT AQUA (2275 2025);
DISPLAY INVISIBLE (2275 2025);
FORCEPROP 2 LAST ROOM IO_SLOT
J 1
(1975 2100);
DISPLAY 0.744681 (1975 2100);
DISPLAY INVISIBLE (1975 2100);
FORCEADD Q_CAP..1
(425 125);
FORCEPROP 1 LAST PART_NUMBER CH31006KB18
J 0
(475 -25);
DISPLAY 0.978723 (475 -25);
DISPLAY INVISIBLE (475 -25);
FORCEPROP 1 LAST PACK_TYPE C0402
J 0
(475 -25);
DISPLAY 0.787234 (475 -25);
FORCEPROP 1 LAST VOLTAGE 50V
J 0
(475 125);
DISPLAY 0.787234 (475 125);
FORCEPROP 1 LAST MATERIAL X7R
J 0
(475 25);
DISPLAY 0.787234 (475 25);
FORCEPROP 1 LAST TOLERANCE 10%
J 0
(475 75);
DISPLAY 0.787234 (475 75);
FORCEPROP 1 LAST VALUE 0.01UF
J 0
(475 175);
DISPLAY 0.787234 (475 175);
FORCEPROP 1 LAST $LOCATION C1915
J 0
(475 225);
DISPLAY 0.787234 (475 225);
FORCEPROP 1 LASTPIN (425 225) $PN 1
J 0
(435 205);
DISPLAY 0.787234 (435 205);
PAINT MONO (435 205);
FORCEPROP 1 LASTPIN (425 25) $PN 2
J 0
(435 5);
DISPLAY 0.787234 (435 5);
PAINT MONO (435 5);
FORCEPROP 2 LAST CDS_LIB pure_quanta
J 0
(425 125);
DISPLAY INVISIBLE (425 125);
FORCEPROP 1 LAST PATH I40
J 0
(475 275);
DISPLAY 0.978723 (475 275);
PAINT WHITE (475 275);
DISPLAY INVISIBLE (475 275);
FORCEPROP 2 LAST CDS_LOCATION C1915
J 0
(475 325);
DISPLAY 1.021277 (475 325);
DISPLAY INVISIBLE (475 325);
FORCEPROP 0 LAST $SEC 1
J 0
(475 275);
DISPLAY 0.680851 (475 275);
PAINT MONO (475 275);
DISPLAY INVISIBLE (475 275);
FORCEPROP 2 LAST CDS_SEC 1
J 0
(475 325);
DISPLAY 1.021277 (475 325);
DISPLAY INVISIBLE (475 325);
FORCEADD Q_CAP..1
(250 1150);
FORCEPROP 1 LAST PART_NUMBER CH4104K1B00
J 0
(300 950);
DISPLAY 0.787234 (300 950);
DISPLAY INVISIBLE (300 950);
FORCEPROP 1 LAST VOLTAGE 25V
J 0
(300 1150);
DISPLAY 0.787234 (300 1150);
FORCEPROP 1 LAST VALUE 0.1UF
J 0
(300 1200);
DISPLAY 0.787234 (300 1200);
FORCEPROP 1 LAST MATERIAL X7R
J 0
(300 1050);
DISPLAY 0.787234 (300 1050);
FORCEPROP 1 LAST PACK_TYPE 0402
J 0
(300 1000);
DISPLAY 0.787234 (300 1000);
FORCEPROP 1 LAST TOLERANCE 10%
J 0
(300 1100);
DISPLAY 0.787234 (300 1100);
FORCEPROP 1 LAST $LOCATION C1905
J 0
(300 1250);
DISPLAY 0.978723 (300 1250);
FORCEPROP 1 LASTPIN (250 1250) $PN 1
J 0
(260 1230);
DISPLAY 0.787234 (260 1230);
FORCEPROP 1 LASTPIN (250 1050) $PN 2
J 0
(260 1030);
DISPLAY 0.787234 (260 1030);
FORCEPROP 2 LAST CDS_LIB pure_quanta
J 0
(250 1150);
PAINT MONO (250 1150);
DISPLAY INVISIBLE (250 1150);
FORCEPROP 1 LAST PATH I41
J 0
(300 1300);
DISPLAY 0.978723 (300 1300);
PAINT WHITE (300 1300);
DISPLAY INVISIBLE (300 1300);
FORCEPROP 2 LAST CDS_LOCATION C1905
J 0
(300 1350);
DISPLAY 1.021277 (300 1350);
DISPLAY INVISIBLE (300 1350);
FORCEPROP 2 LAST $SEC 1
J 0
(300 1350);
DISPLAY 0.680851 (300 1350);
PAINT MONO (300 1350);
DISPLAY INVISIBLE (300 1350);
FORCEPROP 2 LAST CDS_SEC 1
J 0
(300 1350);
DISPLAY 1.021277 (300 1350);
DISPLAY INVISIBLE (300 1350);
FORCEADD Q_CAP..1
(0 1150);
FORCEPROP 1 LAST PART_NUMBER CH31006KB18
J 0
(50 1000);
DISPLAY 0.978723 (50 1000);
DISPLAY INVISIBLE (50 1000);
FORCEPROP 1 LAST VALUE 0.01UF
J 0
(50 1200);
DISPLAY 0.787234 (50 1200);
FORCEPROP 1 LAST TOLERANCE 10%
J 0
(50 1100);
DISPLAY 0.787234 (50 1100);
FORCEPROP 1 LAST MATERIAL X7R
J 0
(50 1050);
DISPLAY 0.787234 (50 1050);
FORCEPROP 1 LAST VOLTAGE 50V
J 0
(50 1150);
DISPLAY 0.787234 (50 1150);
FORCEPROP 1 LAST PACK_TYPE C0402
J 0
(50 1000);
DISPLAY 0.787234 (50 1000);
FORCEPROP 1 LAST $LOCATION C1901
J 0
(50 1250);
DISPLAY 0.787234 (50 1250);
FORCEPROP 1 LASTPIN (0 1250) $PN 1
J 0
(10 1230);
DISPLAY 0.638298 (10 1230);
PAINT MONO (10 1230);
FORCEPROP 1 LASTPIN (0 1050) $PN 2
J 0
(10 1030);
DISPLAY 0.638298 (10 1030);
PAINT MONO (10 1030);
FORCEPROP 2 LAST CDS_LIB pure_quanta
J 0
(0 1150);
DISPLAY INVISIBLE (0 1150);
FORCEPROP 1 LAST PATH I42
J 0
(50 1300);
DISPLAY 0.978723 (50 1300);
PAINT WHITE (50 1300);
DISPLAY INVISIBLE (50 1300);
FORCEPROP 2 LAST CDS_LOCATION C1901
J 0
(50 1350);
DISPLAY 1.021277 (50 1350);
DISPLAY INVISIBLE (50 1350);
FORCEPROP 0 LAST $SEC 1
J 0
(50 1300);
DISPLAY 0.680851 (50 1300);
PAINT MONO (50 1300);
DISPLAY INVISIBLE (50 1300);
FORCEPROP 2 LAST CDS_SEC 1
J 0
(50 1350);
DISPLAY 1.021277 (50 1350);
DISPLAY INVISIBLE (50 1350);
FORCEADD Q_CAP..1
(-250 1150);
FORCEPROP 1 LAST PART_NUMBER CH31006KB18
J 0
(-200 1000);
DISPLAY 0.978723 (-200 1000);
DISPLAY INVISIBLE (-200 1000);
FORCEPROP 1 LAST TOLERANCE 10%
J 0
(-200 1100);
DISPLAY 0.787234 (-200 1100);
FORCEPROP 1 LAST PACK_TYPE C0402
J 0
(-200 1000);
DISPLAY 0.787234 (-200 1000);
FORCEPROP 1 LAST VALUE 0.01UF
J 0
(-200 1200);
DISPLAY 0.787234 (-200 1200);
FORCEPROP 1 LAST VOLTAGE 50V
J 0
(-200 1150);
DISPLAY 0.787234 (-200 1150);
FORCEPROP 1 LAST MATERIAL X7R
J 0
(-200 1050);
DISPLAY 0.787234 (-200 1050);
FORCEPROP 1 LAST $LOCATION C1895
J 0
(-200 1250);
DISPLAY 0.787234 (-200 1250);
FORCEPROP 1 LASTPIN (-250 1250) $PN 1
J 0
(-240 1230);
DISPLAY 0.638298 (-240 1230);
PAINT MONO (-240 1230);
FORCEPROP 1 LASTPIN (-250 1050) $PN 2
J 0
(-240 1030);
DISPLAY 0.638298 (-240 1030);
PAINT MONO (-240 1030);
FORCEPROP 2 LAST CDS_LIB pure_quanta
J 0
(-250 1150);
DISPLAY INVISIBLE (-250 1150);
FORCEPROP 1 LAST PATH I43
J 0
(-200 1300);
DISPLAY 0.978723 (-200 1300);
PAINT WHITE (-200 1300);
DISPLAY INVISIBLE (-200 1300);
FORCEPROP 2 LAST CDS_LOCATION C1895
J 0
(-200 1350);
DISPLAY 1.021277 (-200 1350);
DISPLAY INVISIBLE (-200 1350);
FORCEPROP 0 LAST $SEC 1
J 0
(-200 1300);
DISPLAY 0.680851 (-200 1300);
PAINT MONO (-200 1300);
DISPLAY INVISIBLE (-200 1300);
FORCEPROP 2 LAST CDS_SEC 1
J 0
(-200 1350);
DISPLAY 1.021277 (-200 1350);
DISPLAY INVISIBLE (-200 1350);
FORCEADD Q_CAP..1
(-525 1150);
FORCEPROP 1 LAST PART_NUMBER CH31006KB18
J 0
(-475 1000);
DISPLAY 0.978723 (-475 1000);
DISPLAY INVISIBLE (-475 1000);
FORCEPROP 1 LAST VALUE 0.01UF
J 0
(-475 1200);
DISPLAY 0.787234 (-475 1200);
FORCEPROP 1 LAST TOLERANCE 10%
J 0
(-475 1100);
DISPLAY 0.787234 (-475 1100);
FORCEPROP 1 LAST MATERIAL X7R
J 0
(-475 1050);
DISPLAY 0.787234 (-475 1050);
FORCEPROP 1 LAST VOLTAGE 50V
J 0
(-475 1150);
DISPLAY 0.787234 (-475 1150);
FORCEPROP 1 LAST PACK_TYPE C0402
J 0
(-475 1000);
DISPLAY 0.787234 (-475 1000);
FORCEPROP 1 LAST $LOCATION C1910
J 0
(-475 1250);
DISPLAY 0.787234 (-475 1250);
FORCEPROP 1 LASTPIN (-525 1250) $PN 1
J 0
(-515 1230);
DISPLAY 0.638298 (-515 1230);
PAINT MONO (-515 1230);
FORCEPROP 1 LASTPIN (-525 1050) $PN 2
J 0
(-515 1030);
DISPLAY 0.638298 (-515 1030);
PAINT MONO (-515 1030);
FORCEPROP 2 LAST CDS_LIB pure_quanta
J 0
(-525 1150);
DISPLAY INVISIBLE (-525 1150);
FORCEPROP 1 LAST PATH I44
J 0
(-475 1300);
DISPLAY 0.978723 (-475 1300);
PAINT WHITE (-475 1300);
DISPLAY INVISIBLE (-475 1300);
FORCEPROP 2 LAST CDS_LOCATION C1910
J 0
(-475 1350);
DISPLAY 1.021277 (-475 1350);
DISPLAY INVISIBLE (-475 1350);
FORCEPROP 0 LAST $SEC 1
J 0
(-475 1300);
DISPLAY 0.680851 (-475 1300);
PAINT MONO (-475 1300);
DISPLAY INVISIBLE (-475 1300);
FORCEPROP 2 LAST CDS_SEC 1
J 0
(-475 1350);
DISPLAY 1.021277 (-475 1350);
DISPLAY INVISIBLE (-475 1350);
FORCEADD Q_CAP..1
(175 125);
FORCEPROP 1 LAST PART_NUMBER CH4104K1B00
J 0
(225 -75);
DISPLAY 0.787234 (225 -75);
DISPLAY INVISIBLE (225 -75);
FORCEPROP 1 LAST MATERIAL X7R
J 0
(225 25);
DISPLAY 0.787234 (225 25);
FORCEPROP 1 LAST TOLERANCE 10%
J 0
(225 75);
DISPLAY 0.787234 (225 75);
FORCEPROP 1 LAST VOLTAGE 25V
J 0
(225 125);
DISPLAY 0.787234 (225 125);
FORCEPROP 1 LAST PACK_TYPE 0402
J 0
(225 -25);
DISPLAY 0.787234 (225 -25);
FORCEPROP 1 LAST VALUE 0.1UF
J 0
(225 175);
DISPLAY 0.787234 (225 175);
FORCEPROP 1 LAST $LOCATION C1906
J 0
(225 225);
DISPLAY 0.978723 (225 225);
FORCEPROP 1 LASTPIN (175 225) $PN 1
J 0
(185 205);
DISPLAY 0.787234 (185 205);
FORCEPROP 1 LASTPIN (175 25) $PN 2
J 0
(185 5);
DISPLAY 0.787234 (185 5);
FORCEPROP 2 LAST CDS_LIB pure_quanta
J 0
(175 125);
PAINT MONO (175 125);
DISPLAY INVISIBLE (175 125);
FORCEPROP 1 LAST PATH I45
J 0
(225 275);
DISPLAY 0.978723 (225 275);
PAINT WHITE (225 275);
DISPLAY INVISIBLE (225 275);
FORCEPROP 2 LAST CDS_LOCATION C1906
J 0
(225 325);
DISPLAY 1.021277 (225 325);
DISPLAY INVISIBLE (225 325);
FORCEPROP 2 LAST $SEC 1
J 0
(225 325);
DISPLAY 0.680851 (225 325);
PAINT MONO (225 325);
DISPLAY INVISIBLE (225 325);
FORCEPROP 2 LAST CDS_SEC 1
J 0
(225 325);
DISPLAY 1.021277 (225 325);
DISPLAY INVISIBLE (225 325);
FORCEADD Q_CAP..1
(-75 125);
FORCEPROP 1 LAST PART_NUMBER CH31006KB18
J 0
(-25 -25);
DISPLAY 0.978723 (-25 -25);
DISPLAY INVISIBLE (-25 -25);
FORCEPROP 1 LAST PACK_TYPE C0402
J 0
(-25 -25);
DISPLAY 0.787234 (-25 -25);
FORCEPROP 1 LAST VOLTAGE 50V
J 0
(-25 125);
DISPLAY 0.787234 (-25 125);
FORCEPROP 1 LAST MATERIAL X7R
J 0
(-25 25);
DISPLAY 0.787234 (-25 25);
FORCEPROP 1 LAST TOLERANCE 10%
J 0
(-25 75);
DISPLAY 0.787234 (-25 75);
FORCEPROP 1 LAST VALUE 0.01UF
J 0
(-25 175);
DISPLAY 0.787234 (-25 175);
FORCEPROP 1 LAST $LOCATION C1902
J 0
(-25 225);
DISPLAY 0.787234 (-25 225);
FORCEPROP 1 LASTPIN (-75 225) $PN 1
J 0
(-65 205);
DISPLAY 0.638298 (-65 205);
PAINT MONO (-65 205);
FORCEPROP 1 LASTPIN (-75 25) $PN 2
J 0
(-65 5);
DISPLAY 0.638298 (-65 5);
PAINT MONO (-65 5);
FORCEPROP 2 LAST CDS_LIB pure_quanta
J 0
(-75 125);
DISPLAY INVISIBLE (-75 125);
FORCEPROP 1 LAST PATH I46
J 0
(-25 275);
DISPLAY 0.978723 (-25 275);
PAINT WHITE (-25 275);
DISPLAY INVISIBLE (-25 275);
FORCEPROP 2 LAST CDS_LOCATION C1902
J 0
(-25 325);
DISPLAY 1.021277 (-25 325);
DISPLAY INVISIBLE (-25 325);
FORCEPROP 0 LAST $SEC 1
J 0
(-25 275);
DISPLAY 0.680851 (-25 275);
PAINT MONO (-25 275);
DISPLAY INVISIBLE (-25 275);
FORCEPROP 2 LAST CDS_SEC 1
J 0
(-25 325);
DISPLAY 1.021277 (-25 325);
DISPLAY INVISIBLE (-25 325);
FORCEADD Q_CAP..1
(-325 125);
FORCEPROP 1 LAST PART_NUMBER CH31006KB18
J 0
(-275 -25);
DISPLAY 0.978723 (-275 -25);
DISPLAY INVISIBLE (-275 -25);
FORCEPROP 1 LAST PACK_TYPE C0402
J 0
(-275 -25);
DISPLAY 0.787234 (-275 -25);
FORCEPROP 1 LAST VALUE 0.01UF
J 0
(-275 175);
DISPLAY 0.787234 (-275 175);
FORCEPROP 1 LAST VOLTAGE 50V
J 0
(-275 125);
DISPLAY 0.787234 (-275 125);
FORCEPROP 1 LAST TOLERANCE 10%
J 0
(-275 75);
DISPLAY 0.787234 (-275 75);
FORCEPROP 1 LAST MATERIAL X7R
J 0
(-275 25);
DISPLAY 0.787234 (-275 25);
FORCEPROP 1 LAST $LOCATION C1896
J 0
(-275 225);
DISPLAY 0.787234 (-275 225);
FORCEPROP 1 LASTPIN (-325 225) $PN 1
J 0
(-315 205);
DISPLAY 0.638298 (-315 205);
PAINT MONO (-315 205);
FORCEPROP 1 LASTPIN (-325 25) $PN 2
J 0
(-315 5);
DISPLAY 0.638298 (-315 5);
PAINT MONO (-315 5);
FORCEPROP 2 LAST CDS_LIB pure_quanta
J 0
(-325 125);
DISPLAY INVISIBLE (-325 125);
FORCEPROP 1 LAST PATH I47
J 0
(-275 275);
DISPLAY 0.978723 (-275 275);
PAINT WHITE (-275 275);
DISPLAY INVISIBLE (-275 275);
FORCEPROP 2 LAST CDS_LOCATION C1896
J 0
(-275 325);
DISPLAY 1.021277 (-275 325);
DISPLAY INVISIBLE (-275 325);
FORCEPROP 0 LAST $SEC 1
J 0
(-275 275);
DISPLAY 0.680851 (-275 275);
PAINT MONO (-275 275);
DISPLAY INVISIBLE (-275 275);
FORCEPROP 2 LAST CDS_SEC 1
J 0
(-275 325);
DISPLAY 1.021277 (-275 325);
DISPLAY INVISIBLE (-275 325);
FORCEADD Q_CAP..1
(-600 125);
FORCEPROP 1 LAST PART_NUMBER CH31006KB18
J 0
(-550 -25);
DISPLAY 0.978723 (-550 -25);
DISPLAY INVISIBLE (-550 -25);
FORCEPROP 1 LAST MATERIAL X7R
J 0
(-550 25);
DISPLAY 0.787234 (-550 25);
FORCEPROP 1 LAST VOLTAGE 50V
J 0
(-550 125);
DISPLAY 0.787234 (-550 125);
FORCEPROP 1 LAST VALUE 0.01UF
J 0
(-550 175);
DISPLAY 0.787234 (-550 175);
FORCEPROP 1 LAST TOLERANCE 10%
J 0
(-550 75);
DISPLAY 0.787234 (-550 75);
FORCEPROP 1 LAST PACK_TYPE C0402
J 0
(-550 -25);
DISPLAY 0.787234 (-550 -25);
FORCEPROP 1 LAST $LOCATION C1911
J 0
(-550 225);
DISPLAY 0.787234 (-550 225);
FORCEPROP 1 LASTPIN (-600 225) $PN 1
J 0
(-590 205);
DISPLAY 0.787234 (-590 205);
PAINT MONO (-590 205);
FORCEPROP 1 LASTPIN (-600 25) $PN 2
J 0
(-590 5);
DISPLAY 0.787234 (-590 5);
PAINT MONO (-590 5);
FORCEPROP 2 LAST CDS_LIB pure_quanta
J 0
(-600 125);
DISPLAY INVISIBLE (-600 125);
FORCEPROP 1 LAST PATH I48
J 0
(-550 275);
DISPLAY 0.978723 (-550 275);
PAINT WHITE (-550 275);
DISPLAY INVISIBLE (-550 275);
FORCEPROP 2 LAST CDS_LOCATION C1911
J 0
(-550 325);
DISPLAY 1.021277 (-550 325);
DISPLAY INVISIBLE (-550 325);
FORCEPROP 0 LAST $SEC 1
J 0
(-550 275);
DISPLAY 0.680851 (-550 275);
PAINT MONO (-550 275);
DISPLAY INVISIBLE (-550 275);
FORCEPROP 2 LAST CDS_SEC 1
J 0
(-550 325);
DISPLAY 1.021277 (-550 325);
DISPLAY INVISIBLE (-550 325);
FORCEADD Q_CAP..1
(1200 -1000);
FORCEPROP 1 LAST PART_NUMBER CH31006KB18
J 0
(1250 -1150);
DISPLAY 0.978723 (1250 -1150);
DISPLAY INVISIBLE (1250 -1150);
FORCEPROP 1 LAST VALUE 0.01UF
J 0
(1250 -950);
DISPLAY 0.787234 (1250 -950);
FORCEPROP 1 LAST TOLERANCE 10%
J 0
(1250 -1050);
DISPLAY 0.787234 (1250 -1050);
FORCEPROP 1 LAST MATERIAL X7R
J 0
(1250 -1100);
DISPLAY 0.787234 (1250 -1100);
FORCEPROP 1 LAST PACK_TYPE C0402
J 0
(1250 -1175);
DISPLAY 0.787234 (1250 -1175);
FORCEPROP 1 LAST VOLTAGE 50V
J 0
(1250 -1000);
DISPLAY 0.787234 (1250 -1000);
FORCEPROP 1 LAST $LOCATION C1142
J 0
(1250 -900);
DISPLAY 0.787234 (1250 -900);
FORCEPROP 1 LASTPIN (1200 -900) $PN 1
J 0
(1210 -920);
DISPLAY 0.638298 (1210 -920);
PAINT MONO (1210 -920);
FORCEPROP 1 LASTPIN (1200 -1100) $PN 2
J 0
(1210 -1120);
DISPLAY 0.638298 (1210 -1120);
PAINT MONO (1210 -1120);
FORCEPROP 2 LAST CDS_LIB pure_quanta
J 0
(1200 -1000);
DISPLAY INVISIBLE (1200 -1000);
FORCEPROP 1 LAST PATH I49
J 0
(1250 -850);
DISPLAY 0.978723 (1250 -850);
PAINT WHITE (1250 -850);
DISPLAY INVISIBLE (1250 -850);
FORCEPROP 2 LAST CDS_LOCATION C1142
J 0
(1250 -800);
DISPLAY 1.021277 (1250 -800);
DISPLAY INVISIBLE (1250 -800);
FORCEPROP 0 LAST $SEC 1
J 0
(1250 -850);
DISPLAY 0.680851 (1250 -850);
PAINT MONO (1250 -850);
DISPLAY INVISIBLE (1250 -850);
FORCEPROP 2 LAST CDS_SEC 1
J 0
(1250 -800);
DISPLAY 1.021277 (1250 -800);
DISPLAY INVISIBLE (1250 -800);
FORCEADD Q_CAP..1
(1950 2375);
FORCEPROP 1 LAST PART_NUMBER CH31006KB18
J 0
(2000 2225);
DISPLAY 0.978723 (2000 2225);
DISPLAY INVISIBLE (2000 2225);
FORCEPROP 1 LAST PACK_TYPE C0402
J 0
(2000 2225);
DISPLAY 0.978723 (2000 2225);
FORCEPROP 1 LAST MATERIAL X7R
J 0
(2000 2275);
DISPLAY 0.978723 (2000 2275);
FORCEPROP 1 LAST TOLERANCE 10%
J 0
(2000 2325);
DISPLAY 0.978723 (2000 2325);
FORCEPROP 1 LAST VOLTAGE 50V
J 0
(2000 2375);
DISPLAY 0.978723 (2000 2375);
FORCEPROP 1 LAST VALUE 0.01UF
J 0
(2000 2425);
DISPLAY 0.978723 (2000 2425);
FORCEPROP 1 LAST $LOCATION C1152
J 0
(2000 2475);
DISPLAY 0.978723 (2000 2475);
FORCEPROP 1 LASTPIN (1950 2475) $PN 1
J 0
(1960 2455);
DISPLAY 0.787234 (1960 2455);
PAINT MONO (1960 2455);
FORCEPROP 1 LASTPIN (1950 2275) $PN 2
J 0
(1960 2255);
DISPLAY 0.787234 (1960 2255);
PAINT MONO (1960 2255);
FORCEPROP 2 LAST CDS_LIB pure_quanta
J 0
(1950 2375);
DISPLAY INVISIBLE (1950 2375);
FORCEPROP 1 LAST PATH I5
J 0
(2000 2525);
DISPLAY 0.978723 (2000 2525);
PAINT WHITE (2000 2525);
DISPLAY INVISIBLE (2000 2525);
FORCEPROP 2 LAST CDS_LOCATION C1152
J 0
(2000 2575);
DISPLAY 1.021277 (2000 2575);
DISPLAY INVISIBLE (2000 2575);
FORCEPROP 0 LAST $SEC 1
J 0
(2000 2525);
DISPLAY 0.680851 (2000 2525);
PAINT MONO (2000 2525);
DISPLAY INVISIBLE (2000 2525);
FORCEPROP 2 LAST CDS_SEC 1
J 0
(2000 2575);
DISPLAY 1.021277 (2000 2575);
DISPLAY INVISIBLE (2000 2575);
FORCEADD Q_CAP..1
(950 -1000);
FORCEPROP 1 LAST PART_NUMBER CH31006KB18
J 0
(1000 -1150);
DISPLAY 0.978723 (1000 -1150);
DISPLAY INVISIBLE (1000 -1150);
FORCEPROP 1 LAST PACK_TYPE C0402
J 0
(1000 -1175);
DISPLAY 0.787234 (1000 -1175);
FORCEPROP 1 LAST VOLTAGE 50V
J 0
(1000 -1000);
DISPLAY 0.787234 (1000 -1000);
FORCEPROP 1 LAST MATERIAL X7R
J 0
(1000 -1100);
DISPLAY 0.787234 (1000 -1100);
FORCEPROP 1 LAST TOLERANCE 10%
J 0
(1000 -1050);
DISPLAY 0.787234 (1000 -1050);
FORCEPROP 1 LAST VALUE 0.01UF
J 0
(1000 -950);
DISPLAY 0.787234 (1000 -950);
FORCEPROP 1 LAST $LOCATION C1138
J 0
(1000 -900);
DISPLAY 0.787234 (1000 -900);
FORCEPROP 1 LASTPIN (950 -900) $PN 1
J 0
(960 -920);
DISPLAY 0.638298 (960 -920);
PAINT MONO (960 -920);
FORCEPROP 1 LASTPIN (950 -1100) $PN 2
J 0
(960 -1120);
DISPLAY 0.638298 (960 -1120);
PAINT MONO (960 -1120);
FORCEPROP 2 LAST CDS_LIB pure_quanta
J 0
(950 -1000);
DISPLAY INVISIBLE (950 -1000);
FORCEPROP 1 LAST PATH I50
J 0
(1000 -850);
DISPLAY 0.978723 (1000 -850);
PAINT WHITE (1000 -850);
DISPLAY INVISIBLE (1000 -850);
FORCEPROP 2 LAST CDS_LOCATION C1138
J 0
(1000 -800);
DISPLAY 1.021277 (1000 -800);
DISPLAY INVISIBLE (1000 -800);
FORCEPROP 0 LAST $SEC 1
J 0
(1000 -850);
DISPLAY 0.680851 (1000 -850);
PAINT MONO (1000 -850);
DISPLAY INVISIBLE (1000 -850);
FORCEPROP 2 LAST CDS_SEC 1
J 0
(1000 -800);
DISPLAY 1.021277 (1000 -800);
DISPLAY INVISIBLE (1000 -800);
FORCEADD Q_CAP..1
(700 -1000);
FORCEPROP 1 LAST PART_NUMBER CH31006KB18
J 0
(750 -1150);
DISPLAY 0.978723 (750 -1150);
DISPLAY INVISIBLE (750 -1150);
FORCEPROP 1 LAST TOLERANCE 10%
J 0
(750 -1050);
DISPLAY 0.787234 (750 -1050);
FORCEPROP 1 LAST PACK_TYPE C0402
J 0
(750 -1175);
DISPLAY 0.787234 (750 -1175);
FORCEPROP 1 LAST VOLTAGE 50V
J 0
(750 -1000);
DISPLAY 0.787234 (750 -1000);
FORCEPROP 1 LAST MATERIAL X7R
J 0
(750 -1100);
DISPLAY 0.787234 (750 -1100);
FORCEPROP 1 LAST VALUE 0.01UF
J 0
(750 -950);
DISPLAY 0.787234 (750 -950);
FORCEPROP 1 LAST $LOCATION C1133
J 0
(750 -900);
DISPLAY 0.787234 (750 -900);
FORCEPROP 1 LASTPIN (700 -900) $PN 1
J 0
(710 -920);
DISPLAY 0.638298 (710 -920);
PAINT MONO (710 -920);
FORCEPROP 1 LASTPIN (700 -1100) $PN 2
J 0
(710 -1120);
DISPLAY 0.638298 (710 -1120);
PAINT MONO (710 -1120);
FORCEPROP 2 LAST CDS_LIB pure_quanta
J 0
(700 -1000);
DISPLAY INVISIBLE (700 -1000);
FORCEPROP 1 LAST PATH I51
J 0
(750 -850);
DISPLAY 0.978723 (750 -850);
PAINT WHITE (750 -850);
DISPLAY INVISIBLE (750 -850);
FORCEPROP 2 LAST CDS_LOCATION C1133
J 0
(750 -800);
DISPLAY 1.021277 (750 -800);
DISPLAY INVISIBLE (750 -800);
FORCEPROP 0 LAST $SEC 1
J 0
(750 -850);
DISPLAY 0.680851 (750 -850);
PAINT MONO (750 -850);
DISPLAY INVISIBLE (750 -850);
FORCEPROP 2 LAST CDS_SEC 1
J 0
(750 -800);
DISPLAY 1.021277 (750 -800);
DISPLAY INVISIBLE (750 -800);
FORCEADD Q_CAP..1
(450 -1000);
FORCEPROP 1 LAST PART_NUMBER CH31006KB18
J 0
(500 -1150);
DISPLAY 0.978723 (500 -1150);
DISPLAY INVISIBLE (500 -1150);
FORCEPROP 1 LAST TOLERANCE 10%
J 0
(500 -1050);
DISPLAY 0.787234 (500 -1050);
FORCEPROP 1 LAST MATERIAL X7R
J 0
(500 -1100);
DISPLAY 0.787234 (500 -1100);
FORCEPROP 1 LAST PACK_TYPE C0402
J 0
(500 -1150);
DISPLAY 0.787234 (500 -1150);
FORCEPROP 1 LAST VOLTAGE 50V
J 0
(500 -1000);
DISPLAY 0.787234 (500 -1000);
FORCEPROP 1 LAST VALUE 0.01UF
J 0
(500 -950);
DISPLAY 0.787234 (500 -950);
FORCEPROP 1 LAST $LOCATION C1127
J 0
(500 -900);
DISPLAY 0.787234 (500 -900);
FORCEPROP 1 LASTPIN (450 -900) $PN 1
J 0
(460 -920);
DISPLAY 0.787234 (460 -920);
PAINT MONO (460 -920);
FORCEPROP 1 LASTPIN (450 -1100) $PN 2
J 0
(460 -1120);
DISPLAY 0.787234 (460 -1120);
PAINT MONO (460 -1120);
FORCEPROP 2 LAST CDS_LIB pure_quanta
J 0
(450 -1000);
DISPLAY INVISIBLE (450 -1000);
FORCEPROP 1 LAST PATH I52
J 0
(500 -850);
DISPLAY 0.978723 (500 -850);
PAINT WHITE (500 -850);
DISPLAY INVISIBLE (500 -850);
FORCEPROP 2 LAST CDS_LOCATION C1127
J 0
(500 -800);
DISPLAY 1.021277 (500 -800);
DISPLAY INVISIBLE (500 -800);
FORCEPROP 0 LAST $SEC 1
J 0
(500 -850);
DISPLAY 0.680851 (500 -850);
PAINT MONO (500 -850);
DISPLAY INVISIBLE (500 -850);
FORCEPROP 2 LAST CDS_SEC 1
J 0
(500 -800);
DISPLAY 1.021277 (500 -800);
DISPLAY INVISIBLE (500 -800);
FORCEADD Q_CAP..1
(1225 -2225);
FORCEPROP 1 LAST PART_NUMBER CH31006KB18
J 0
(1275 -2375);
DISPLAY 0.404255 (1275 -2375);
DISPLAY INVISIBLE (1275 -2375);
FORCEPROP 1 LAST MATERIAL X7R
J 0
(1275 -2325);
DISPLAY 0.638298 (1275 -2325);
FORCEPROP 1 LAST VALUE 0.01UF
J 0
(1275 -2175);
DISPLAY 0.638298 (1275 -2175);
FORCEPROP 1 LAST VOLTAGE 50V
J 0
(1275 -2225);
DISPLAY 0.638298 (1275 -2225);
FORCEPROP 1 LAST PACK_TYPE C0402
J 0
(1275 -2425);
DISPLAY 0.638298 (1275 -2425);
FORCEPROP 1 LAST TOLERANCE 10%
J 0
(1275 -2275);
DISPLAY 0.638298 (1275 -2275);
FORCEPROP 1 LAST $LOCATION C1913
J 0
(1275 -2125);
DISPLAY 0.638298 (1275 -2125);
FORCEPROP 1 LASTPIN (1225 -2125) $PN 1
J 0
(1235 -2145);
DISPLAY 0.787234 (1235 -2145);
PAINT MONO (1235 -2145);
FORCEPROP 1 LASTPIN (1225 -2325) $PN 2
J 0
(1235 -2345);
DISPLAY 0.787234 (1235 -2345);
PAINT MONO (1235 -2345);
FORCEPROP 2 LAST CDS_LIB pure_quanta
J 0
(1225 -2225);
DISPLAY INVISIBLE (1225 -2225);
FORCEPROP 1 LAST PATH I53
J 0
(1275 -2075);
DISPLAY 0.978723 (1275 -2075);
PAINT WHITE (1275 -2075);
DISPLAY INVISIBLE (1275 -2075);
FORCEPROP 2 LAST CDS_LOCATION C1913
J 0
(1275 -2025);
DISPLAY 1.021277 (1275 -2025);
DISPLAY INVISIBLE (1275 -2025);
FORCEPROP 0 LAST $SEC 1
J 0
(1275 -2075);
DISPLAY 0.680851 (1275 -2075);
PAINT MONO (1275 -2075);
DISPLAY INVISIBLE (1275 -2075);
FORCEPROP 2 LAST CDS_SEC 1
J 0
(1275 -2025);
DISPLAY 1.021277 (1275 -2025);
DISPLAY INVISIBLE (1275 -2025);
FORCEADD Q_CAP..1
(925 -2225);
FORCEPROP 1 LAST PART_NUMBER CH4104K1B00
J 0
(975 -2425);
DISPLAY 0.787234 (975 -2425);
DISPLAY INVISIBLE (975 -2425);
FORCEPROP 1 LAST TOLERANCE 10%
J 0
(975 -2275);
DISPLAY 0.787234 (975 -2275);
FORCEPROP 1 LAST MATERIAL X7R
J 0
(975 -2325);
DISPLAY 0.787234 (975 -2325);
FORCEPROP 1 LAST VALUE 0.1UF
J 0
(975 -2175);
DISPLAY 0.787234 (975 -2175);
FORCEPROP 1 LAST VOLTAGE 25V
J 0
(975 -2225);
DISPLAY 0.787234 (975 -2225);
FORCEPROP 1 LAST PACK_TYPE 0402
J 0
(975 -2375);
DISPLAY 0.787234 (975 -2375);
FORCEPROP 1 LAST $LOCATION C1947
J 0
(975 -2125);
DISPLAY 0.978723 (975 -2125);
FORCEPROP 1 LASTPIN (925 -2125) $PN 1
J 0
(935 -2145);
DISPLAY 0.787234 (935 -2145);
PAINT MONO (935 -2145);
FORCEPROP 1 LASTPIN (925 -2325) $PN 2
J 0
(935 -2345);
DISPLAY 0.787234 (935 -2345);
PAINT MONO (935 -2345);
FORCEPROP 2 LAST CDS_LIB pure_quanta
J 0
(925 -2225);
DISPLAY INVISIBLE (925 -2225);
FORCEPROP 1 LAST PATH I54
J 0
(975 -2075);
DISPLAY 0.978723 (975 -2075);
PAINT WHITE (975 -2075);
DISPLAY INVISIBLE (975 -2075);
FORCEPROP 0 LAST CDS_LOCATION C1947
J 0
(975 -2075);
DISPLAY 1.021277 (975 -2075);
DISPLAY INVISIBLE (975 -2075);
FORCEPROP 0 LAST $SEC 1
J 0
(975 -2075);
DISPLAY 0.680851 (975 -2075);
PAINT MONO (975 -2075);
DISPLAY INVISIBLE (975 -2075);
FORCEPROP 0 LAST CDS_SEC 1
J 0
(975 -2075);
DISPLAY 1.021277 (975 -2075);
DISPLAY INVISIBLE (975 -2075);
FORCEADD Q_CAP..1
(575 -2200);
FORCEPROP 1 LAST PART_NUMBER CH6101MEB01
J 0
(625 -2350);
DISPLAY 0.638298 (625 -2350);
DISPLAY INVISIBLE (625 -2350);
FORCEPROP 1 LAST MATERIAL X6S
J 0
(625 -2300);
DISPLAY 0.638298 (625 -2300);
FORCEPROP 1 LAST TOLERANCE 20%
J 0
(625 -2250);
DISPLAY 0.638298 (625 -2250);
FORCEPROP 1 LAST PACK_TYPE C0402
J 0
(625 -2400);
DISPLAY 0.638298 (625 -2400);
FORCEPROP 1 LAST VALUE 10UF
J 0
(625 -2150);
DISPLAY 0.638298 (625 -2150);
FORCEPROP 1 LAST VOLTAGE 6.3V
J 0
(625 -2200);
DISPLAY 0.638298 (625 -2200);
FORCEPROP 1 LAST $LOCATION C1940
J 0
(625 -2100);
DISPLAY 0.978723 (625 -2100);
FORCEPROP 1 LASTPIN (575 -2100) $PN 1
J 0
(585 -2120);
DISPLAY 0.787234 (585 -2120);
PAINT MONO (585 -2120);
FORCEPROP 1 LASTPIN (575 -2300) $PN 2
J 0
(585 -2320);
DISPLAY 0.787234 (585 -2320);
PAINT MONO (585 -2320);
FORCEPROP 2 LAST CDS_LIB pure_quanta
J 0
(575 -2200);
DISPLAY INVISIBLE (575 -2200);
FORCEPROP 1 LAST PATH I55
J 0
(625 -2050);
DISPLAY 0.978723 (625 -2050);
PAINT WHITE (625 -2050);
DISPLAY INVISIBLE (625 -2050);
FORCEPROP 0 LAST CDS_LOCATION C1940
J 0
(625 -2050);
DISPLAY 1.021277 (625 -2050);
DISPLAY INVISIBLE (625 -2050);
FORCEPROP 0 LAST $SEC 1
J 0
(625 -2050);
DISPLAY 0.680851 (625 -2050);
PAINT MONO (625 -2050);
DISPLAY INVISIBLE (625 -2050);
FORCEPROP 0 LAST CDS_SEC 1
J 0
(625 -2050);
DISPLAY 1.021277 (625 -2050);
DISPLAY INVISIBLE (625 -2050);
FORCEADD Q_CAP..1
(200 -1000);
FORCEPROP 1 LAST PART_NUMBER CH4104K1B00
J 0
(250 -1200);
DISPLAY 0.787234 (250 -1200);
DISPLAY INVISIBLE (250 -1200);
FORCEPROP 1 LAST PACK_TYPE 0402
J 0
(250 -1150);
DISPLAY 0.787234 (250 -1150);
FORCEPROP 1 LAST MATERIAL X7R
J 0
(250 -1100);
DISPLAY 0.787234 (250 -1100);
FORCEPROP 1 LAST TOLERANCE 10%
J 0
(250 -1050);
DISPLAY 0.787234 (250 -1050);
FORCEPROP 1 LAST VALUE 0.1UF
J 0
(250 -950);
DISPLAY 0.787234 (250 -950);
FORCEPROP 1 LAST VOLTAGE 25V
J 0
(250 -1000);
DISPLAY 0.787234 (250 -1000);
FORCEPROP 1 LAST $LOCATION C1122
J 0
(250 -900);
DISPLAY 0.978723 (250 -900);
FORCEPROP 1 LASTPIN (200 -900) $PN 1
J 0
(210 -920);
DISPLAY 0.787234 (210 -920);
FORCEPROP 1 LASTPIN (200 -1100) $PN 2
J 0
(210 -1120);
DISPLAY 0.787234 (210 -1120);
FORCEPROP 2 LAST CDS_LIB pure_quanta
J 0
(200 -1000);
PAINT MONO (200 -1000);
DISPLAY INVISIBLE (200 -1000);
FORCEPROP 1 LAST PATH I56
J 0
(250 -850);
DISPLAY 0.978723 (250 -850);
PAINT WHITE (250 -850);
DISPLAY INVISIBLE (250 -850);
FORCEPROP 2 LAST CDS_LOCATION C1122
J 0
(250 -800);
DISPLAY 1.021277 (250 -800);
DISPLAY INVISIBLE (250 -800);
FORCEPROP 2 LAST $SEC 1
J 0
(250 -800);
DISPLAY 0.680851 (250 -800);
PAINT MONO (250 -800);
DISPLAY INVISIBLE (250 -800);
FORCEPROP 2 LAST CDS_SEC 1
J 0
(250 -800);
DISPLAY 1.021277 (250 -800);
DISPLAY INVISIBLE (250 -800);
FORCEADD Q_CAP..1
(-50 -1000);
FORCEPROP 1 LAST PART_NUMBER CH31006KB18
J 0
(0 -1150);
DISPLAY 0.404255 (0 -1150);
DISPLAY INVISIBLE (0 -1150);
FORCEPROP 1 LAST MATERIAL X7R
J 0
(0 -1100);
DISPLAY 0.638298 (0 -1100);
FORCEPROP 1 LAST VOLTAGE 50V
J 0
(0 -1000);
DISPLAY 0.638298 (0 -1000);
FORCEPROP 1 LAST TOLERANCE 10%
J 0
(0 -1050);
DISPLAY 0.638298 (0 -1050);
FORCEPROP 1 LAST PACK_TYPE C0402
J 0
(0 -1200);
DISPLAY 0.638298 (0 -1200);
FORCEPROP 1 LAST VALUE 0.01UF
J 0
(0 -950);
DISPLAY 0.638298 (0 -950);
FORCEPROP 1 LAST $LOCATION C1900
J 0
(0 -900);
DISPLAY 0.638298 (0 -900);
FORCEPROP 1 LASTPIN (-50 -900) $PN 1
J 0
(-40 -920);
DISPLAY 0.787234 (-40 -920);
PAINT MONO (-40 -920);
FORCEPROP 1 LASTPIN (-50 -1100) $PN 2
J 0
(-40 -1120);
DISPLAY 0.787234 (-40 -1120);
PAINT MONO (-40 -1120);
FORCEPROP 2 LAST CDS_LIB pure_quanta
J 0
(-50 -1000);
DISPLAY INVISIBLE (-50 -1000);
FORCEPROP 1 LAST PATH I57
J 0
(0 -850);
DISPLAY 0.978723 (0 -850);
PAINT WHITE (0 -850);
DISPLAY INVISIBLE (0 -850);
FORCEPROP 2 LAST CDS_LOCATION C1900
J 0
(0 -800);
DISPLAY 1.021277 (0 -800);
DISPLAY INVISIBLE (0 -800);
FORCEPROP 0 LAST $SEC 1
J 0
(0 -850);
DISPLAY 0.680851 (0 -850);
PAINT MONO (0 -850);
DISPLAY INVISIBLE (0 -850);
FORCEPROP 2 LAST CDS_SEC 1
J 0
(0 -800);
DISPLAY 1.021277 (0 -800);
DISPLAY INVISIBLE (0 -800);
FORCEADD Q_CAP..1
(-300 -1000);
FORCEPROP 1 LAST PART_NUMBER CH31006KB18
J 0
(-250 -1150);
DISPLAY 0.404255 (-250 -1150);
DISPLAY INVISIBLE (-250 -1150);
FORCEPROP 1 LAST VOLTAGE 50V
J 0
(-250 -1000);
DISPLAY 0.638298 (-250 -1000);
FORCEPROP 1 LAST PACK_TYPE C0402
J 0
(-250 -1200);
DISPLAY 0.638298 (-250 -1200);
FORCEPROP 1 LAST TOLERANCE 10%
J 0
(-250 -1050);
DISPLAY 0.638298 (-250 -1050);
FORCEPROP 1 LAST VALUE 0.01UF
J 0
(-250 -950);
DISPLAY 0.638298 (-250 -950);
FORCEPROP 1 LAST MATERIAL X7R
J 0
(-250 -1100);
DISPLAY 0.638298 (-250 -1100);
FORCEPROP 1 LAST $LOCATION C1894
J 0
(-250 -900);
DISPLAY 0.638298 (-250 -900);
FORCEPROP 1 LASTPIN (-300 -900) $PN 1
J 0
(-290 -920);
DISPLAY 0.787234 (-290 -920);
PAINT MONO (-290 -920);
FORCEPROP 1 LASTPIN (-300 -1100) $PN 2
J 0
(-290 -1120);
DISPLAY 0.787234 (-290 -1120);
PAINT MONO (-290 -1120);
FORCEPROP 2 LAST CDS_LIB pure_quanta
J 0
(-300 -1000);
DISPLAY INVISIBLE (-300 -1000);
FORCEPROP 1 LAST PATH I58
J 0
(-250 -850);
DISPLAY 0.978723 (-250 -850);
PAINT WHITE (-250 -850);
DISPLAY INVISIBLE (-250 -850);
FORCEPROP 2 LAST CDS_LOCATION C1894
J 0
(-250 -800);
DISPLAY 1.021277 (-250 -800);
DISPLAY INVISIBLE (-250 -800);
FORCEPROP 0 LAST $SEC 1
J 0
(-250 -850);
DISPLAY 0.680851 (-250 -850);
PAINT MONO (-250 -850);
DISPLAY INVISIBLE (-250 -850);
FORCEPROP 2 LAST CDS_SEC 1
J 0
(-250 -800);
DISPLAY 1.021277 (-250 -800);
DISPLAY INVISIBLE (-250 -800);
FORCEADD Q_CAP..1
(-575 -1000);
FORCEPROP 1 LAST PART_NUMBER CH31006KB18
J 0
(-525 -1150);
DISPLAY 0.404255 (-525 -1150);
DISPLAY INVISIBLE (-525 -1150);
FORCEPROP 1 LAST MATERIAL X7R
J 0
(-525 -1100);
DISPLAY 0.638298 (-525 -1100);
FORCEPROP 1 LAST PACK_TYPE C0402
J 0
(-525 -1200);
DISPLAY 0.638298 (-525 -1200);
FORCEPROP 1 LAST VALUE 0.01UF
J 0
(-525 -950);
DISPLAY 0.638298 (-525 -950);
FORCEPROP 1 LAST VOLTAGE 50V
J 0
(-525 -1000);
DISPLAY 0.638298 (-525 -1000);
FORCEPROP 1 LAST TOLERANCE 10%
J 0
(-525 -1050);
DISPLAY 0.638298 (-525 -1050);
FORCEPROP 1 LAST $LOCATION C1909
J 0
(-525 -900);
DISPLAY 0.638298 (-525 -900);
FORCEPROP 1 LASTPIN (-575 -900) $PN 1
J 0
(-565 -920);
DISPLAY 0.787234 (-565 -920);
PAINT MONO (-565 -920);
FORCEPROP 1 LASTPIN (-575 -1100) $PN 2
J 0
(-565 -1120);
DISPLAY 0.787234 (-565 -1120);
PAINT MONO (-565 -1120);
FORCEPROP 2 LAST CDS_LIB pure_quanta
J 0
(-575 -1000);
DISPLAY INVISIBLE (-575 -1000);
FORCEPROP 1 LAST PATH I59
J 0
(-525 -850);
DISPLAY 0.978723 (-525 -850);
PAINT WHITE (-525 -850);
DISPLAY INVISIBLE (-525 -850);
FORCEPROP 2 LAST CDS_LOCATION C1909
J 0
(-525 -800);
DISPLAY 1.021277 (-525 -800);
DISPLAY INVISIBLE (-525 -800);
FORCEPROP 0 LAST $SEC 1
J 0
(-525 -850);
DISPLAY 0.680851 (-525 -850);
PAINT MONO (-525 -850);
DISPLAY INVISIBLE (-525 -850);
FORCEPROP 2 LAST CDS_SEC 1
J 0
(-525 -800);
DISPLAY 1.021277 (-525 -800);
DISPLAY INVISIBLE (-525 -800);
FORCEADD Q_RES..1
(200 -2025);
FORCEPROP 1 LAST PART_NUMBER CS-1003F900
J 0
(50 -1950);
DISPLAY 0.510638 (50 -1950);
DISPLAY INVISIBLE (50 -1950);
FORCEPROP 1 LAST MATERIAL CHIP
J 0
(525 -2025);
DISPLAY 0.638298 (525 -2025);
FORCEPROP 1 LAST WATTAGE 1/10W
J 2
(375 -1900);
DISPLAY 0.510638 (375 -1900);
FORCEPROP 1 LAST VALUE 1
J 2
(400 -2025);
DISPLAY 0.638298 (400 -2025);
FORCEPROP 1 LAST TOLERANCE 1%
J 0
(425 -2025);
DISPLAY 0.638298 (425 -2025);
FORCEPROP 1 LAST PACK_TYPE 0603LF
J 0
(50 -1900);
DISPLAY 0.510638 (50 -1900);
FORCEPROP 1 LAST $LOCATION R3349
J 0
(-75 -2025);
DISPLAY 0.978723 (-75 -2025);
FORCEPROP 2 LAST CDS_LIB pure_quanta
J 0
(200 -2025);
PAINT MONO (200 -2025);
DISPLAY INVISIBLE (200 -2025);
FORCEPROP 1 LAST PATH I60
J 0
(150 -1875);
DISPLAY 0.978723 (150 -1875);
PAINT WHITE (150 -1875);
DISPLAY INVISIBLE (150 -1875);
FORCEPROP 2 LAST CDS_LOCATION R3349
J 0
(150 -1825);
DISPLAY 1.021277 (150 -1825);
DISPLAY INVISIBLE (150 -1825);
FORCEPROP 2 LAST $SEC 1
J 0
(150 -1825);
DISPLAY 0.680851 (150 -1825);
PAINT MONO (150 -1825);
DISPLAY INVISIBLE (150 -1825);
FORCEPROP 2 LAST CDS_SEC 1
J 0
(150 -1825);
DISPLAY 1.021277 (150 -1825);
DISPLAY INVISIBLE (150 -1825);
FORCEPROP 1 LASTPIN (100 -2025) $PN 1
J 0
(112 -2013);
DISPLAY 0.787234 (112 -2013);
DISPLAY INVISIBLE (112 -2013);
FORCEPROP 1 LASTPIN (300 -2025) $PN 2
J 0
(262 -2013);
DISPLAY 0.787234 (262 -2013);
DISPLAY INVISIBLE (262 -2013);
FORCEADD UNIVERSAL_POWER..1
(-225 -1875);
FORCEPROP 3 LASTPIN (-225 -1925) SIG_NAME P3V3_AUX\g
J 0
(-215 -1915);
DISPLAY 0.659574 (-215 -1915);
PAINT MONO (-215 -1915);
DISPLAY INVISIBLE (-215 -1915);
FORCEPROP 1 LAST HDL_POWER P3V3_AUX
J 1
(-225 -1825);
DISPLAY 0.872340 (-225 -1825);
PAINT GREEN (-225 -1825);
FORCEPROP 2 LAST CDS_LIB logical_power
J 0
(-225 -1875);
PAINT MONO (-225 -1875);
DISPLAY INVISIBLE (-225 -1875);
FORCEPROP 1 LAST PATH I61
J 0
(-175 -1850);
DISPLAY 0.872340 (-175 -1850);
PAINT AQUA (-175 -1850);
DISPLAY INVISIBLE (-175 -1850);
FORCEADD Q_CAP..1
(-825 1150);
FORCEPROP 1 LAST PART_NUMBER CH4104K1B00
J 0
(-775 950);
DISPLAY 0.787234 (-775 950);
DISPLAY INVISIBLE (-775 950);
FORCEPROP 1 LAST PACK_TYPE 0402
J 0
(-775 1000);
DISPLAY 0.638298 (-775 1000);
FORCEPROP 1 LAST MATERIAL X7R
J 0
(-775 1050);
DISPLAY 0.638298 (-775 1050);
FORCEPROP 1 LAST VOLTAGE 25V
J 0
(-775 1150);
DISPLAY 0.638298 (-775 1150);
FORCEPROP 1 LAST VALUE 0.1UF
J 0
(-775 1200);
DISPLAY 0.638298 (-775 1200);
FORCEPROP 1 LAST TOLERANCE 10%
J 0
(-775 1100);
DISPLAY 0.638298 (-775 1100);
FORCEPROP 1 LAST $LOCATION C1945
J 0
(-775 1250);
DISPLAY 0.787234 (-775 1250);
FORCEPROP 1 LASTPIN (-825 1250) $PN 1
J 0
(-815 1230);
DISPLAY 0.787234 (-815 1230);
PAINT MONO (-815 1230);
FORCEPROP 1 LASTPIN (-825 1050) $PN 2
J 0
(-815 1030);
DISPLAY 0.787234 (-815 1030);
PAINT MONO (-815 1030);
FORCEPROP 2 LAST CDS_LIB pure_quanta
J 0
(-825 1150);
DISPLAY INVISIBLE (-825 1150);
FORCEPROP 1 LAST PATH I62
J 0
(-775 1300);
DISPLAY 0.978723 (-775 1300);
PAINT WHITE (-775 1300);
DISPLAY INVISIBLE (-775 1300);
FORCEPROP 0 LAST CDS_LOCATION C1945
J 0
(-775 1300);
DISPLAY 1.021277 (-775 1300);
DISPLAY INVISIBLE (-775 1300);
FORCEPROP 0 LAST $SEC 1
J 0
(-775 1300);
DISPLAY 0.680851 (-775 1300);
PAINT MONO (-775 1300);
DISPLAY INVISIBLE (-775 1300);
FORCEPROP 0 LAST CDS_SEC 1
J 0
(-775 1300);
DISPLAY 1.021277 (-775 1300);
DISPLAY INVISIBLE (-775 1300);
FORCEADD Q_RES..1
(-1475 1350);
FORCEPROP 1 LAST PART_NUMBER CS-1003F900
J 0
(-1625 1425);
DISPLAY 0.510638 (-1625 1425);
DISPLAY INVISIBLE (-1625 1425);
FORCEPROP 1 LAST PACK_TYPE 0603LF
J 0
(-1625 1475);
DISPLAY 0.510638 (-1625 1475);
FORCEPROP 1 LAST MATERIAL CHIP
J 0
(-1150 1350);
DISPLAY 0.638298 (-1150 1350);
FORCEPROP 1 LAST WATTAGE 1/10W
J 2
(-1300 1475);
DISPLAY 0.510638 (-1300 1475);
FORCEPROP 1 LAST TOLERANCE 1%
J 0
(-1250 1350);
DISPLAY 0.638298 (-1250 1350);
FORCEPROP 1 LAST VALUE 1
J 2
(-1275 1350);
DISPLAY 0.638298 (-1275 1350);
FORCEPROP 1 LAST $LOCATION R3346
J 0
(-1750 1350);
DISPLAY 0.978723 (-1750 1350);
FORCEPROP 2 LAST CDS_LIB pure_quanta
J 0
(-1475 1350);
PAINT MONO (-1475 1350);
DISPLAY INVISIBLE (-1475 1350);
FORCEPROP 1 LAST PATH I63
J 0
(-1525 1500);
DISPLAY 0.978723 (-1525 1500);
PAINT WHITE (-1525 1500);
DISPLAY INVISIBLE (-1525 1500);
FORCEPROP 2 LAST CDS_LOCATION R3346
J 0
(-1525 1550);
DISPLAY 1.021277 (-1525 1550);
DISPLAY INVISIBLE (-1525 1550);
FORCEPROP 2 LAST $SEC 1
J 0
(-1525 1550);
DISPLAY 0.680851 (-1525 1550);
PAINT MONO (-1525 1550);
DISPLAY INVISIBLE (-1525 1550);
FORCEPROP 2 LAST CDS_SEC 1
J 0
(-1525 1550);
DISPLAY 1.021277 (-1525 1550);
DISPLAY INVISIBLE (-1525 1550);
FORCEPROP 1 LASTPIN (-1575 1350) $PN 1
J 0
(-1563 1362);
DISPLAY 0.787234 (-1563 1362);
DISPLAY INVISIBLE (-1563 1362);
FORCEPROP 1 LASTPIN (-1375 1350) $PN 2
J 0
(-1413 1362);
DISPLAY 0.787234 (-1413 1362);
DISPLAY INVISIBLE (-1413 1362);
FORCEADD Q_CAP..1
(-1175 1175);
FORCEPROP 1 LAST PART_NUMBER CH6101MEB01
J 0
(-1125 1025);
DISPLAY 0.638298 (-1125 1025);
DISPLAY INVISIBLE (-1125 1025);
FORCEPROP 1 LAST PACK_TYPE C0402
J 0
(-1125 975);
DISPLAY 0.638298 (-1125 975);
FORCEPROP 1 LAST MATERIAL X6S
J 0
(-1125 1075);
DISPLAY 0.638298 (-1125 1075);
FORCEPROP 1 LAST VOLTAGE 6.3V
J 0
(-1125 1175);
DISPLAY 0.638298 (-1125 1175);
FORCEPROP 1 LAST TOLERANCE 20%
J 0
(-1125 1125);
DISPLAY 0.638298 (-1125 1125);
FORCEPROP 1 LAST VALUE 10UF
J 0
(-1125 1225);
DISPLAY 0.638298 (-1125 1225);
FORCEPROP 1 LAST $LOCATION C1938
J 0
(-1125 1275);
DISPLAY 0.978723 (-1125 1275);
FORCEPROP 1 LASTPIN (-1175 1275) $PN 1
J 0
(-1165 1255);
DISPLAY 0.787234 (-1165 1255);
PAINT MONO (-1165 1255);
FORCEPROP 1 LASTPIN (-1175 1075) $PN 2
J 0
(-1165 1055);
DISPLAY 0.787234 (-1165 1055);
PAINT MONO (-1165 1055);
FORCEPROP 2 LAST CDS_LIB pure_quanta
J 0
(-1175 1175);
DISPLAY INVISIBLE (-1175 1175);
FORCEPROP 1 LAST PATH I64
J 0
(-1125 1325);
DISPLAY 0.978723 (-1125 1325);
PAINT WHITE (-1125 1325);
DISPLAY INVISIBLE (-1125 1325);
FORCEPROP 0 LAST CDS_LOCATION C1938
J 0
(-1125 1325);
DISPLAY 1.021277 (-1125 1325);
DISPLAY INVISIBLE (-1125 1325);
FORCEPROP 0 LAST $SEC 1
J 0
(-1125 1325);
DISPLAY 0.680851 (-1125 1325);
PAINT MONO (-1125 1325);
DISPLAY INVISIBLE (-1125 1325);
FORCEPROP 0 LAST CDS_SEC 1
J 0
(-1125 1325);
DISPLAY 1.021277 (-1125 1325);
DISPLAY INVISIBLE (-1125 1325);
FORCEADD Q_CAP..1
(-900 125);
FORCEPROP 1 LAST PART_NUMBER CH4104K1B00
J 0
(-850 -75);
DISPLAY 0.787234 (-850 -75);
DISPLAY INVISIBLE (-850 -75);
FORCEPROP 1 LAST PACK_TYPE 0402
J 0
(-850 -25);
DISPLAY 0.787234 (-850 -25);
FORCEPROP 1 LAST MATERIAL X7R
J 0
(-850 25);
DISPLAY 0.787234 (-850 25);
FORCEPROP 1 LAST VOLTAGE 25V
J 0
(-850 125);
DISPLAY 0.787234 (-850 125);
FORCEPROP 1 LAST VALUE 0.1UF
J 0
(-850 175);
DISPLAY 0.787234 (-850 175);
FORCEPROP 1 LAST TOLERANCE 10%
J 0
(-850 75);
DISPLAY 0.787234 (-850 75);
FORCEPROP 1 LAST $LOCATION C1946
J 0
(-850 225);
DISPLAY 0.978723 (-850 225);
FORCEPROP 1 LASTPIN (-900 225) $PN 1
J 0
(-890 205);
DISPLAY 0.787234 (-890 205);
PAINT MONO (-890 205);
FORCEPROP 1 LASTPIN (-900 25) $PN 2
J 0
(-890 5);
DISPLAY 0.787234 (-890 5);
PAINT MONO (-890 5);
FORCEPROP 2 LAST CDS_LIB pure_quanta
J 0
(-900 125);
DISPLAY INVISIBLE (-900 125);
FORCEPROP 1 LAST PATH I65
J 0
(-850 275);
DISPLAY 0.978723 (-850 275);
PAINT WHITE (-850 275);
DISPLAY INVISIBLE (-850 275);
FORCEPROP 0 LAST CDS_LOCATION C1946
J 0
(-850 275);
DISPLAY 1.021277 (-850 275);
DISPLAY INVISIBLE (-850 275);
FORCEPROP 0 LAST $SEC 1
J 0
(-850 275);
DISPLAY 0.680851 (-850 275);
PAINT MONO (-850 275);
DISPLAY INVISIBLE (-850 275);
FORCEPROP 0 LAST CDS_SEC 1
J 0
(-850 275);
DISPLAY 1.021277 (-850 275);
DISPLAY INVISIBLE (-850 275);
FORCEADD Q_CAP..1
(-1250 150);
FORCEPROP 1 LAST PART_NUMBER CH6101MEB01
J 0
(-1200 0);
DISPLAY 0.638298 (-1200 0);
DISPLAY INVISIBLE (-1200 0);
FORCEPROP 1 LAST MATERIAL X6S
J 0
(-1200 50);
DISPLAY 0.638298 (-1200 50);
FORCEPROP 1 LAST PACK_TYPE C0402
J 0
(-1200 -50);
DISPLAY 0.638298 (-1200 -50);
FORCEPROP 1 LAST TOLERANCE 20%
J 0
(-1200 100);
DISPLAY 0.638298 (-1200 100);
FORCEPROP 1 LAST VALUE 10UF
J 0
(-1200 200);
DISPLAY 0.638298 (-1200 200);
FORCEPROP 1 LAST VOLTAGE 6.3V
J 0
(-1200 150);
DISPLAY 0.638298 (-1200 150);
FORCEPROP 1 LAST $LOCATION C1939
J 0
(-1200 250);
DISPLAY 0.978723 (-1200 250);
FORCEPROP 1 LASTPIN (-1250 250) $PN 1
J 0
(-1240 230);
DISPLAY 0.787234 (-1240 230);
PAINT MONO (-1240 230);
FORCEPROP 1 LASTPIN (-1250 50) $PN 2
J 0
(-1240 30);
DISPLAY 0.787234 (-1240 30);
PAINT MONO (-1240 30);
FORCEPROP 2 LAST CDS_LIB pure_quanta
J 0
(-1250 150);
DISPLAY INVISIBLE (-1250 150);
FORCEPROP 1 LAST PATH I66
J 0
(-1200 300);
DISPLAY 0.978723 (-1200 300);
PAINT WHITE (-1200 300);
DISPLAY INVISIBLE (-1200 300);
FORCEPROP 0 LAST CDS_LOCATION C1939
J 0
(-1200 300);
DISPLAY 1.021277 (-1200 300);
DISPLAY INVISIBLE (-1200 300);
FORCEPROP 0 LAST $SEC 1
J 0
(-1200 300);
DISPLAY 0.680851 (-1200 300);
PAINT MONO (-1200 300);
DISPLAY INVISIBLE (-1200 300);
FORCEPROP 0 LAST CDS_SEC 1
J 0
(-1200 300);
DISPLAY 1.021277 (-1200 300);
DISPLAY INVISIBLE (-1200 300);
FORCEADD Q_RES..1
(-1475 325);
FORCEPROP 1 LAST PART_NUMBER CS-1003F900
J 0
(-1625 400);
DISPLAY 0.510638 (-1625 400);
DISPLAY INVISIBLE (-1625 400);
FORCEPROP 1 LAST WATTAGE 1/10W
J 2
(-1300 450);
DISPLAY 0.510638 (-1300 450);
FORCEPROP 1 LAST PACK_TYPE 0603LF
J 0
(-1625 450);
DISPLAY 0.510638 (-1625 450);
FORCEPROP 1 LAST MATERIAL CHIP
J 0
(-1150 325);
DISPLAY 0.638298 (-1150 325);
FORCEPROP 1 LAST TOLERANCE 1%
J 0
(-1250 325);
DISPLAY 0.638298 (-1250 325);
FORCEPROP 1 LAST VALUE 1
J 2
(-1275 325);
DISPLAY 0.638298 (-1275 325);
FORCEPROP 1 LAST $LOCATION R3348
J 0
(-1750 325);
DISPLAY 0.978723 (-1750 325);
FORCEPROP 2 LAST CDS_LIB pure_quanta
J 0
(-1475 325);
PAINT MONO (-1475 325);
DISPLAY INVISIBLE (-1475 325);
FORCEPROP 1 LAST PATH I67
J 0
(-1525 475);
DISPLAY 0.978723 (-1525 475);
PAINT WHITE (-1525 475);
DISPLAY INVISIBLE (-1525 475);
FORCEPROP 2 LAST CDS_LOCATION R3348
J 0
(-1525 525);
DISPLAY 1.021277 (-1525 525);
DISPLAY INVISIBLE (-1525 525);
FORCEPROP 2 LAST $SEC 1
J 0
(-1525 525);
DISPLAY 0.680851 (-1525 525);
PAINT MONO (-1525 525);
DISPLAY INVISIBLE (-1525 525);
FORCEPROP 2 LAST CDS_SEC 1
J 0
(-1525 525);
DISPLAY 1.021277 (-1525 525);
DISPLAY INVISIBLE (-1525 525);
FORCEPROP 1 LASTPIN (-1575 325) $PN 1
J 0
(-1563 337);
DISPLAY 0.787234 (-1563 337);
DISPLAY INVISIBLE (-1563 337);
FORCEPROP 1 LASTPIN (-1375 325) $PN 2
J 0
(-1413 337);
DISPLAY 0.787234 (-1413 337);
DISPLAY INVISIBLE (-1413 337);
FORCEADD UNIVERSAL_POWER..1
(-1900 1500);
FORCEPROP 3 LASTPIN (-1900 1450) SIG_NAME P3V3_AUX\g
J 0
(-1890 1460);
DISPLAY 0.659574 (-1890 1460);
PAINT MONO (-1890 1460);
DISPLAY INVISIBLE (-1890 1460);
FORCEPROP 1 LAST HDL_POWER P3V3_AUX
J 1
(-1900 1550);
DISPLAY 0.872340 (-1900 1550);
PAINT GREEN (-1900 1550);
FORCEPROP 2 LAST CDS_LIB logical_power
J 0
(-1900 1500);
PAINT MONO (-1900 1500);
DISPLAY INVISIBLE (-1900 1500);
FORCEPROP 1 LAST PATH I68
J 0
(-1850 1525);
DISPLAY 0.872340 (-1850 1525);
PAINT AQUA (-1850 1525);
DISPLAY INVISIBLE (-1850 1525);
FORCEADD UNIVERSAL_POWER..1
(-1900 475);
FORCEPROP 3 LASTPIN (-1900 425) SIG_NAME P3V3_AUX\g
J 0
(-1890 435);
DISPLAY 0.659574 (-1890 435);
PAINT MONO (-1890 435);
DISPLAY INVISIBLE (-1890 435);
FORCEPROP 1 LAST HDL_POWER P3V3_AUX
J 1
(-1900 525);
DISPLAY 0.872340 (-1900 525);
PAINT GREEN (-1900 525);
FORCEPROP 2 LAST CDS_LIB logical_power
J 0
(-1900 475);
PAINT MONO (-1900 475);
DISPLAY INVISIBLE (-1900 475);
FORCEPROP 1 LAST PATH I69
J 0
(-1850 500);
DISPLAY 0.872340 (-1850 500);
PAINT AQUA (-1850 500);
DISPLAY INVISIBLE (-1850 500);
FORCEADD Q_CAP..1
(-875 -1000);
FORCEPROP 1 LAST PART_NUMBER CH4104K1B00
J 0
(-825 -1200);
DISPLAY 0.787234 (-825 -1200);
DISPLAY INVISIBLE (-825 -1200);
FORCEPROP 1 LAST VALUE 0.1UF
J 0
(-825 -950);
DISPLAY 0.787234 (-825 -950);
FORCEPROP 1 LAST VOLTAGE 25V
J 0
(-825 -1000);
DISPLAY 0.787234 (-825 -1000);
FORCEPROP 1 LAST TOLERANCE 10%
J 0
(-825 -1050);
DISPLAY 0.787234 (-825 -1050);
FORCEPROP 1 LAST PACK_TYPE 0402
J 0
(-825 -1150);
DISPLAY 0.787234 (-825 -1150);
FORCEPROP 1 LAST MATERIAL X7R
J 0
(-825 -1100);
DISPLAY 0.787234 (-825 -1100);
FORCEPROP 1 LAST $LOCATION C1944
J 0
(-825 -900);
DISPLAY 0.978723 (-825 -900);
FORCEPROP 1 LASTPIN (-875 -900) $PN 1
J 0
(-865 -920);
DISPLAY 0.787234 (-865 -920);
PAINT MONO (-865 -920);
FORCEPROP 1 LASTPIN (-875 -1100) $PN 2
J 0
(-865 -1120);
DISPLAY 0.787234 (-865 -1120);
PAINT MONO (-865 -1120);
FORCEPROP 2 LAST CDS_LIB pure_quanta
J 0
(-875 -1000);
DISPLAY INVISIBLE (-875 -1000);
FORCEPROP 1 LAST PATH I70
J 0
(-825 -850);
DISPLAY 0.978723 (-825 -850);
PAINT WHITE (-825 -850);
DISPLAY INVISIBLE (-825 -850);
FORCEPROP 0 LAST CDS_LOCATION C1944
J 0
(-825 -850);
DISPLAY 1.021277 (-825 -850);
DISPLAY INVISIBLE (-825 -850);
FORCEPROP 0 LAST $SEC 1
J 0
(-825 -850);
DISPLAY 0.680851 (-825 -850);
PAINT MONO (-825 -850);
DISPLAY INVISIBLE (-825 -850);
FORCEPROP 0 LAST CDS_SEC 1
J 0
(-825 -850);
DISPLAY 1.021277 (-825 -850);
DISPLAY INVISIBLE (-825 -850);
FORCEADD Q_CAP..1
(-1225 -975);
FORCEPROP 1 LAST PART_NUMBER CH6101MEB01
J 0
(-1175 -1125);
DISPLAY 0.638298 (-1175 -1125);
DISPLAY INVISIBLE (-1175 -1125);
FORCEPROP 1 LAST MATERIAL X6S
J 0
(-1175 -1075);
DISPLAY 0.638298 (-1175 -1075);
FORCEPROP 1 LAST TOLERANCE 20%
J 0
(-1175 -1025);
DISPLAY 0.638298 (-1175 -1025);
FORCEPROP 1 LAST VOLTAGE 6.3V
J 0
(-1175 -975);
DISPLAY 0.638298 (-1175 -975);
FORCEPROP 1 LAST VALUE 10UF
J 0
(-1175 -925);
DISPLAY 0.638298 (-1175 -925);
FORCEPROP 1 LAST PACK_TYPE C0402
J 0
(-1175 -1175);
DISPLAY 0.638298 (-1175 -1175);
FORCEPROP 1 LAST $LOCATION C1937
J 0
(-1175 -875);
DISPLAY 0.978723 (-1175 -875);
FORCEPROP 1 LASTPIN (-1225 -875) $PN 1
J 0
(-1215 -895);
DISPLAY 0.787234 (-1215 -895);
PAINT MONO (-1215 -895);
FORCEPROP 1 LASTPIN (-1225 -1075) $PN 2
J 0
(-1215 -1095);
DISPLAY 0.787234 (-1215 -1095);
PAINT MONO (-1215 -1095);
FORCEPROP 2 LAST CDS_LIB pure_quanta
J 0
(-1225 -975);
DISPLAY INVISIBLE (-1225 -975);
FORCEPROP 1 LAST PATH I71
J 0
(-1175 -825);
DISPLAY 0.978723 (-1175 -825);
PAINT WHITE (-1175 -825);
DISPLAY INVISIBLE (-1175 -825);
FORCEPROP 0 LAST CDS_LOCATION C1937
J 0
(-1175 -825);
DISPLAY 1.021277 (-1175 -825);
DISPLAY INVISIBLE (-1175 -825);
FORCEPROP 0 LAST $SEC 1
J 0
(-1175 -825);
DISPLAY 0.680851 (-1175 -825);
PAINT MONO (-1175 -825);
DISPLAY INVISIBLE (-1175 -825);
FORCEPROP 0 LAST CDS_SEC 1
J 0
(-1175 -825);
DISPLAY 1.021277 (-1175 -825);
DISPLAY INVISIBLE (-1175 -825);
FORCEADD Q_RES..1
(-1450 -800);
FORCEPROP 1 LAST PART_NUMBER CS-1003F900
J 0
(-1600 -725);
DISPLAY 0.510638 (-1600 -725);
DISPLAY INVISIBLE (-1600 -725);
FORCEPROP 1 LAST TOLERANCE 1%
J 0
(-1225 -800);
DISPLAY 0.638298 (-1225 -800);
FORCEPROP 1 LAST PACK_TYPE 0603LF
J 0
(-1600 -675);
DISPLAY 0.510638 (-1600 -675);
FORCEPROP 1 LAST WATTAGE 1/10W
J 2
(-1275 -675);
DISPLAY 0.510638 (-1275 -675);
FORCEPROP 1 LAST VALUE 1
J 2
(-1250 -800);
DISPLAY 0.638298 (-1250 -800);
FORCEPROP 1 LAST MATERIAL CHIP
J 0
(-1125 -800);
DISPLAY 0.638298 (-1125 -800);
FORCEPROP 1 LAST $LOCATION R3347
J 0
(-1725 -800);
DISPLAY 0.978723 (-1725 -800);
FORCEPROP 2 LAST CDS_LIB pure_quanta
J 0
(-1450 -800);
PAINT MONO (-1450 -800);
DISPLAY INVISIBLE (-1450 -800);
FORCEPROP 1 LAST PATH I72
J 0
(-1500 -650);
DISPLAY 0.978723 (-1500 -650);
PAINT WHITE (-1500 -650);
DISPLAY INVISIBLE (-1500 -650);
FORCEPROP 2 LAST CDS_LOCATION R3347
J 0
(-1500 -600);
DISPLAY 1.021277 (-1500 -600);
DISPLAY INVISIBLE (-1500 -600);
FORCEPROP 2 LAST $SEC 1
J 0
(-1500 -600);
DISPLAY 0.680851 (-1500 -600);
PAINT MONO (-1500 -600);
DISPLAY INVISIBLE (-1500 -600);
FORCEPROP 2 LAST CDS_SEC 1
J 0
(-1500 -600);
DISPLAY 1.021277 (-1500 -600);
DISPLAY INVISIBLE (-1500 -600);
FORCEPROP 1 LASTPIN (-1550 -800) $PN 1
J 0
(-1538 -788);
DISPLAY 0.787234 (-1538 -788);
DISPLAY INVISIBLE (-1538 -788);
FORCEPROP 1 LASTPIN (-1350 -800) $PN 2
J 0
(-1388 -788);
DISPLAY 0.787234 (-1388 -788);
DISPLAY INVISIBLE (-1388 -788);
FORCEADD UNIVERSAL_POWER..1
(-1225 -1850);
FORCEPROP 3 LASTPIN (-1225 -1900) SIG_NAME P3V3_AUX_FPGA_VCCIO4\g
J 0
(-1215 -1890);
DISPLAY 0.659574 (-1215 -1890);
PAINT MONO (-1215 -1890);
DISPLAY INVISIBLE (-1215 -1890);
FORCEPROP 1 LAST HDL_POWER P3V3_AUX_FPGA_VCCIO4
J 1
(-1225 -1800);
DISPLAY 0.872340 (-1225 -1800);
PAINT GREEN (-1225 -1800);
FORCEPROP 2 LAST CDS_LIB logical_power
J 0
(-1225 -1850);
PAINT MONO (-1225 -1850);
DISPLAY INVISIBLE (-1225 -1850);
FORCEPROP 1 LAST PATH I73
J 0
(-1175 -1825);
DISPLAY 0.872340 (-1175 -1825);
PAINT AQUA (-1175 -1825);
DISPLAY INVISIBLE (-1175 -1825);
FORCEADD Q_CAP..1
(-1225 -2175);
FORCEPROP 1 LAST PART_NUMBER CH31006KB18
J 0
(-1175 -2325);
DISPLAY 0.510638 (-1175 -2325);
DISPLAY INVISIBLE (-1175 -2325);
FORCEPROP 1 LAST TOLERANCE 10%
J 0
(-1175 -2225);
DISPLAY 0.638298 (-1175 -2225);
FORCEPROP 1 LAST VOLTAGE 50V
J 0
(-1175 -2175);
DISPLAY 0.638298 (-1175 -2175);
FORCEPROP 1 LAST MATERIAL X7R
J 0
(-1175 -2275);
DISPLAY 0.638298 (-1175 -2275);
FORCEPROP 1 LAST VALUE 0.01UF
J 0
(-1175 -2125);
DISPLAY 0.638298 (-1175 -2125);
FORCEPROP 1 LAST PACK_TYPE C0402
J 0
(-1175 -2375);
DISPLAY 0.638298 (-1175 -2375);
FORCEPROP 1 LAST $LOCATION C1899
J 0
(-1175 -2075);
DISPLAY 0.638298 (-1175 -2075);
FORCEPROP 1 LASTPIN (-1225 -2075) $PN 1
J 0
(-1215 -2095);
DISPLAY 0.787234 (-1215 -2095);
PAINT MONO (-1215 -2095);
FORCEPROP 1 LASTPIN (-1225 -2275) $PN 2
J 0
(-1215 -2295);
DISPLAY 0.787234 (-1215 -2295);
PAINT MONO (-1215 -2295);
FORCEPROP 2 LAST CDS_LIB pure_quanta
J 0
(-1225 -2175);
DISPLAY INVISIBLE (-1225 -2175);
FORCEPROP 1 LAST PATH I74
J 0
(-1175 -2025);
DISPLAY 0.978723 (-1175 -2025);
PAINT WHITE (-1175 -2025);
DISPLAY INVISIBLE (-1175 -2025);
FORCEPROP 2 LAST CDS_LOCATION C1899
J 0
(-1175 -1975);
DISPLAY 1.021277 (-1175 -1975);
DISPLAY INVISIBLE (-1175 -1975);
FORCEPROP 0 LAST $SEC 1
J 0
(-1175 -2025);
DISPLAY 0.680851 (-1175 -2025);
PAINT MONO (-1175 -2025);
DISPLAY INVISIBLE (-1175 -2025);
FORCEPROP 2 LAST CDS_SEC 1
J 0
(-1175 -1975);
DISPLAY 1.021277 (-1175 -1975);
DISPLAY INVISIBLE (-1175 -1975);
FORCEADD UNIVERSAL_GND..1
(-1225 -2500);
FORCEPROP 3 LASTPIN (-1225 -2450) SIG_NAME GND\g
J 0
(-1215 -2440);
DISPLAY 0.659574 (-1215 -2440);
PAINT MONO (-1215 -2440);
DISPLAY INVISIBLE (-1215 -2440);
FORCEPROP 2 LAST CDS_LIB logical_power
J 0
(-1225 -2500);
DISPLAY INVISIBLE (-1225 -2500);
FORCEPROP 1 LAST HDL_POWER GND
J 1
(-1200 -2575);
DISPLAY 0.872340 (-1200 -2575);
PAINT GREEN (-1200 -2575);
DISPLAY INVISIBLE (-1200 -2575);
FORCEPROP 1 LAST PATH I75
J 0
(-1150 -2500);
DISPLAY 0.872340 (-1150 -2500);
PAINT AQUA (-1150 -2500);
DISPLAY INVISIBLE (-1150 -2500);
FORCEPROP 2 LAST ROOM IO_SLOT
J 1
(-1450 -2425);
DISPLAY 0.744681 (-1450 -2425);
DISPLAY INVISIBLE (-1450 -2425);
FORCEADD Q_CAP..1
(-1475 -2175);
FORCEPROP 1 LAST PART_NUMBER CH31006KB18
J 0
(-1425 -2325);
DISPLAY 0.404255 (-1425 -2325);
DISPLAY INVISIBLE (-1425 -2325);
FORCEPROP 1 LAST MATERIAL X7R
J 0
(-1425 -2275);
DISPLAY 0.638298 (-1425 -2275);
FORCEPROP 1 LAST TOLERANCE 10%
J 0
(-1425 -2225);
DISPLAY 0.638298 (-1425 -2225);
FORCEPROP 1 LAST VOLTAGE 50V
J 0
(-1425 -2175);
DISPLAY 0.638298 (-1425 -2175);
FORCEPROP 1 LAST VALUE 0.01UF
J 0
(-1425 -2125);
DISPLAY 0.638298 (-1425 -2125);
FORCEPROP 1 LAST PACK_TYPE C0402
J 0
(-1425 -2375);
DISPLAY 0.638298 (-1425 -2375);
FORCEPROP 1 LAST $LOCATION C1893
J 0
(-1425 -2075);
DISPLAY 0.638298 (-1425 -2075);
FORCEPROP 1 LASTPIN (-1475 -2075) $PN 1
J 0
(-1465 -2095);
DISPLAY 0.787234 (-1465 -2095);
PAINT MONO (-1465 -2095);
FORCEPROP 1 LASTPIN (-1475 -2275) $PN 2
J 0
(-1465 -2295);
DISPLAY 0.787234 (-1465 -2295);
PAINT MONO (-1465 -2295);
FORCEPROP 2 LAST CDS_LIB pure_quanta
J 0
(-1475 -2175);
DISPLAY INVISIBLE (-1475 -2175);
FORCEPROP 1 LAST PATH I76
J 0
(-1425 -2025);
DISPLAY 0.978723 (-1425 -2025);
PAINT WHITE (-1425 -2025);
DISPLAY INVISIBLE (-1425 -2025);
FORCEPROP 2 LAST CDS_LOCATION C1893
J 0
(-1425 -1975);
DISPLAY 1.021277 (-1425 -1975);
DISPLAY INVISIBLE (-1425 -1975);
FORCEPROP 0 LAST $SEC 1
J 0
(-1425 -2025);
DISPLAY 0.680851 (-1425 -2025);
PAINT MONO (-1425 -2025);
DISPLAY INVISIBLE (-1425 -2025);
FORCEPROP 2 LAST CDS_SEC 1
J 0
(-1425 -1975);
DISPLAY 1.021277 (-1425 -1975);
DISPLAY INVISIBLE (-1425 -1975);
FORCEADD Q_CAP..1
(-1750 -2175);
FORCEPROP 1 LAST PART_NUMBER CH31006KB18
J 0
(-1700 -2325);
DISPLAY 0.404255 (-1700 -2325);
DISPLAY INVISIBLE (-1700 -2325);
FORCEPROP 1 LAST VOLTAGE 50V
J 0
(-1700 -2175);
DISPLAY 0.638298 (-1700 -2175);
FORCEPROP 1 LAST PACK_TYPE C0402
J 0
(-1700 -2375);
DISPLAY 0.638298 (-1700 -2375);
FORCEPROP 1 LAST TOLERANCE 10%
J 0
(-1700 -2225);
DISPLAY 0.638298 (-1700 -2225);
FORCEPROP 1 LAST VALUE 0.01UF
J 0
(-1700 -2125);
DISPLAY 0.638298 (-1700 -2125);
FORCEPROP 1 LAST MATERIAL X7R
J 0
(-1700 -2275);
DISPLAY 0.638298 (-1700 -2275);
FORCEPROP 1 LAST $LOCATION C1908
J 0
(-1700 -2075);
DISPLAY 0.638298 (-1700 -2075);
FORCEPROP 1 LASTPIN (-1750 -2075) $PN 1
J 0
(-1740 -2095);
DISPLAY 0.787234 (-1740 -2095);
PAINT MONO (-1740 -2095);
FORCEPROP 1 LASTPIN (-1750 -2275) $PN 2
J 0
(-1740 -2295);
DISPLAY 0.787234 (-1740 -2295);
PAINT MONO (-1740 -2295);
FORCEPROP 2 LAST CDS_LIB pure_quanta
J 0
(-1750 -2175);
DISPLAY INVISIBLE (-1750 -2175);
FORCEPROP 1 LAST PATH I77
J 0
(-1700 -2025);
DISPLAY 0.978723 (-1700 -2025);
PAINT WHITE (-1700 -2025);
DISPLAY INVISIBLE (-1700 -2025);
FORCEPROP 2 LAST CDS_LOCATION C1908
J 0
(-1700 -1975);
DISPLAY 1.021277 (-1700 -1975);
DISPLAY INVISIBLE (-1700 -1975);
FORCEPROP 0 LAST $SEC 1
J 0
(-1700 -2025);
DISPLAY 0.680851 (-1700 -2025);
PAINT MONO (-1700 -2025);
DISPLAY INVISIBLE (-1700 -2025);
FORCEPROP 2 LAST CDS_SEC 1
J 0
(-1700 -1975);
DISPLAY 1.021277 (-1700 -1975);
DISPLAY INVISIBLE (-1700 -1975);
FORCEADD UNIVERSAL_POWER..1
(-1875 -650);
FORCEPROP 3 LASTPIN (-1875 -700) SIG_NAME P3V3_AUX\g
J 0
(-1865 -690);
DISPLAY 0.659574 (-1865 -690);
PAINT MONO (-1865 -690);
DISPLAY INVISIBLE (-1865 -690);
FORCEPROP 1 LAST HDL_POWER P3V3_AUX
J 1
(-1875 -600);
DISPLAY 0.872340 (-1875 -600);
PAINT GREEN (-1875 -600);
FORCEPROP 2 LAST CDS_LIB logical_power
J 0
(-1875 -650);
PAINT MONO (-1875 -650);
DISPLAY INVISIBLE (-1875 -650);
FORCEPROP 1 LAST PATH I78
J 0
(-1825 -625);
DISPLAY 0.872340 (-1825 -625);
PAINT AQUA (-1825 -625);
DISPLAY INVISIBLE (-1825 -625);
FORCEADD UNIVERSAL_GND..1
(-2400 -350);
FORCEPROP 3 LASTPIN (-2400 -300) SIG_NAME GND\g
J 0
(-2390 -290);
DISPLAY 0.659574 (-2390 -290);
PAINT MONO (-2390 -290);
DISPLAY INVISIBLE (-2390 -290);
FORCEPROP 2 LAST CDS_LIB logical_power
J 0
(-2400 -350);
DISPLAY INVISIBLE (-2400 -350);
FORCEPROP 1 LAST HDL_POWER GND
J 1
(-2375 -425);
DISPLAY 0.872340 (-2375 -425);
PAINT GREEN (-2375 -425);
DISPLAY INVISIBLE (-2375 -425);
FORCEPROP 1 LAST PATH I79
J 0
(-2325 -350);
DISPLAY 0.872340 (-2325 -350);
PAINT AQUA (-2325 -350);
DISPLAY INVISIBLE (-2325 -350);
FORCEPROP 2 LAST ROOM IO_SLOT
J 1
(-2625 -275);
DISPLAY 0.744681 (-2625 -275);
DISPLAY INVISIBLE (-2625 -275);
FORCEADD UNIVERSAL_POWER..1
(1500 1475);
FORCEPROP 3 LASTPIN (1500 1425) SIG_NAME P3V3_AUX_FPGA_VCCIO0\g
J 0
(1510 1435);
DISPLAY 0.659574 (1510 1435);
PAINT MONO (1510 1435);
DISPLAY INVISIBLE (1510 1435);
FORCEPROP 1 LAST HDL_POWER P3V3_AUX_FPGA_VCCIO0
J 1
(1500 1525);
DISPLAY 0.872340 (1500 1525);
PAINT GREEN (1500 1525);
FORCEPROP 2 LAST CDS_LIB logical_power
J 0
(1500 1475);
PAINT MONO (1500 1475);
DISPLAY INVISIBLE (1500 1475);
FORCEPROP 1 LAST PATH I8
J 0
(1550 1500);
DISPLAY 0.872340 (1550 1500);
PAINT AQUA (1550 1500);
DISPLAY INVISIBLE (1550 1500);
FORCEADD Q_CAP..1
(-2050 -2175);
FORCEPROP 1 LAST PART_NUMBER CH4104K1B00
J 0
(-2000 -2375);
DISPLAY 0.787234 (-2000 -2375);
DISPLAY INVISIBLE (-2000 -2375);
FORCEPROP 1 LAST VALUE 0.1UF
J 0
(-2000 -2125);
DISPLAY 0.787234 (-2000 -2125);
FORCEPROP 1 LAST VOLTAGE 25V
J 0
(-2000 -2175);
DISPLAY 0.787234 (-2000 -2175);
FORCEPROP 1 LAST TOLERANCE 10%
J 0
(-2000 -2225);
DISPLAY 0.787234 (-2000 -2225);
FORCEPROP 1 LAST MATERIAL X7R
J 0
(-2000 -2275);
DISPLAY 0.787234 (-2000 -2275);
FORCEPROP 1 LAST PACK_TYPE 0402
J 0
(-2000 -2325);
DISPLAY 0.787234 (-2000 -2325);
FORCEPROP 1 LAST $LOCATION C1942
J 0
(-2000 -2075);
DISPLAY 0.978723 (-2000 -2075);
FORCEPROP 1 LASTPIN (-2050 -2075) $PN 1
J 0
(-2040 -2095);
DISPLAY 0.787234 (-2040 -2095);
PAINT MONO (-2040 -2095);
FORCEPROP 1 LASTPIN (-2050 -2275) $PN 2
J 0
(-2040 -2295);
DISPLAY 0.787234 (-2040 -2295);
PAINT MONO (-2040 -2295);
FORCEPROP 2 LAST CDS_LIB pure_quanta
J 0
(-2050 -2175);
DISPLAY INVISIBLE (-2050 -2175);
FORCEPROP 1 LAST PATH I80
J 0
(-2000 -2025);
DISPLAY 0.978723 (-2000 -2025);
PAINT WHITE (-2000 -2025);
DISPLAY INVISIBLE (-2000 -2025);
FORCEPROP 0 LAST CDS_LOCATION C1942
J 0
(-2000 -2025);
DISPLAY 1.021277 (-2000 -2025);
DISPLAY INVISIBLE (-2000 -2025);
FORCEPROP 0 LAST $SEC 1
J 0
(-2000 -2025);
DISPLAY 0.680851 (-2000 -2025);
PAINT MONO (-2000 -2025);
DISPLAY INVISIBLE (-2000 -2025);
FORCEPROP 0 LAST CDS_SEC 1
J 0
(-2000 -2025);
DISPLAY 1.021277 (-2000 -2025);
DISPLAY INVISIBLE (-2000 -2025);
FORCEADD Q_RES..1
(-2575 -1975);
FORCEPROP 1 LAST PART_NUMBER CS-1003F900
J 0
(-2725 -1900);
DISPLAY 0.510638 (-2725 -1900);
DISPLAY INVISIBLE (-2725 -1900);
FORCEPROP 1 LAST WATTAGE 1/10W
J 2
(-2400 -1850);
DISPLAY 0.510638 (-2400 -1850);
FORCEPROP 1 LAST VALUE 1
J 2
(-2375 -1975);
DISPLAY 0.638298 (-2375 -1975);
FORCEPROP 1 LAST MATERIAL CHIP
J 0
(-2250 -1975);
DISPLAY 0.638298 (-2250 -1975);
FORCEPROP 1 LAST TOLERANCE 1%
J 0
(-2350 -1975);
DISPLAY 0.638298 (-2350 -1975);
FORCEPROP 1 LAST PACK_TYPE 0603LF
J 0
(-2725 -1850);
DISPLAY 0.510638 (-2725 -1850);
FORCEPROP 1 LAST $LOCATION R3345
J 0
(-2850 -1975);
DISPLAY 0.978723 (-2850 -1975);
FORCEPROP 2 LAST CDS_LIB pure_quanta
J 0
(-2575 -1975);
PAINT MONO (-2575 -1975);
DISPLAY INVISIBLE (-2575 -1975);
FORCEPROP 1 LAST PATH I81
J 0
(-2625 -1825);
DISPLAY 0.978723 (-2625 -1825);
PAINT WHITE (-2625 -1825);
DISPLAY INVISIBLE (-2625 -1825);
FORCEPROP 2 LAST CDS_LOCATION R3345
J 0
(-2625 -1775);
DISPLAY 1.021277 (-2625 -1775);
DISPLAY INVISIBLE (-2625 -1775);
FORCEPROP 2 LAST $SEC 1
J 0
(-2625 -1775);
DISPLAY 0.680851 (-2625 -1775);
PAINT MONO (-2625 -1775);
DISPLAY INVISIBLE (-2625 -1775);
FORCEPROP 2 LAST CDS_SEC 1
J 0
(-2625 -1775);
DISPLAY 1.021277 (-2625 -1775);
DISPLAY INVISIBLE (-2625 -1775);
FORCEPROP 1 LASTPIN (-2675 -1975) $PN 1
J 0
(-2663 -1963);
DISPLAY 0.787234 (-2663 -1963);
DISPLAY INVISIBLE (-2663 -1963);
FORCEPROP 1 LASTPIN (-2475 -1975) $PN 2
J 0
(-2513 -1963);
DISPLAY 0.787234 (-2513 -1963);
DISPLAY INVISIBLE (-2513 -1963);
FORCEADD Q_CAP..1
(-2400 -2150);
FORCEPROP 1 LAST PART_NUMBER CH6101MEB01
J 0
(-2350 -2300);
DISPLAY 0.638298 (-2350 -2300);
DISPLAY INVISIBLE (-2350 -2300);
FORCEPROP 1 LAST VOLTAGE 6.3V
J 0
(-2350 -2150);
DISPLAY 0.638298 (-2350 -2150);
FORCEPROP 1 LAST PACK_TYPE C0402
J 0
(-2350 -2350);
DISPLAY 0.638298 (-2350 -2350);
FORCEPROP 1 LAST TOLERANCE 20%
J 0
(-2350 -2200);
DISPLAY 0.638298 (-2350 -2200);
FORCEPROP 1 LAST MATERIAL X6S
J 0
(-2350 -2250);
DISPLAY 0.638298 (-2350 -2250);
FORCEPROP 1 LAST VALUE 10UF
J 0
(-2350 -2100);
DISPLAY 0.638298 (-2350 -2100);
FORCEPROP 1 LAST $LOCATION C1935
J 0
(-2350 -2050);
DISPLAY 0.978723 (-2350 -2050);
FORCEPROP 1 LASTPIN (-2400 -2050) $PN 1
J 0
(-2390 -2070);
DISPLAY 0.787234 (-2390 -2070);
PAINT MONO (-2390 -2070);
FORCEPROP 1 LASTPIN (-2400 -2250) $PN 2
J 0
(-2390 -2270);
DISPLAY 0.787234 (-2390 -2270);
PAINT MONO (-2390 -2270);
FORCEPROP 2 LAST CDS_LIB pure_quanta
J 0
(-2400 -2150);
DISPLAY INVISIBLE (-2400 -2150);
FORCEPROP 1 LAST PATH I82
J 0
(-2350 -2000);
DISPLAY 0.978723 (-2350 -2000);
PAINT WHITE (-2350 -2000);
DISPLAY INVISIBLE (-2350 -2000);
FORCEPROP 0 LAST CDS_LOCATION C1935
J 0
(-2350 -2000);
DISPLAY 1.021277 (-2350 -2000);
DISPLAY INVISIBLE (-2350 -2000);
FORCEPROP 0 LAST $SEC 1
J 0
(-2350 -2000);
DISPLAY 0.680851 (-2350 -2000);
PAINT MONO (-2350 -2000);
DISPLAY INVISIBLE (-2350 -2000);
FORCEPROP 0 LAST CDS_SEC 1
J 0
(-2350 -2000);
DISPLAY 1.021277 (-2350 -2000);
DISPLAY INVISIBLE (-2350 -2000);
FORCEADD Q_CAP..1
(1500 1150);
FORCEPROP 1 LAST PART_NUMBER CH31006KB18
J 0
(1550 1000);
DISPLAY 0.978723 (1550 1000);
DISPLAY INVISIBLE (1550 1000);
FORCEPROP 1 LAST TOLERANCE 10%
J 0
(1550 1100);
DISPLAY 0.638298 (1550 1100);
FORCEPROP 1 LAST MATERIAL X7R
J 0
(1550 1050);
DISPLAY 0.638298 (1550 1050);
FORCEPROP 1 LAST VOLTAGE 50V
J 0
(1550 1150);
DISPLAY 0.638298 (1550 1150);
FORCEPROP 1 LAST PACK_TYPE C0402
J 0
(1550 1000);
DISPLAY 0.638298 (1550 1000);
FORCEPROP 1 LAST VALUE 0.01UF
J 0
(1550 1200);
DISPLAY 0.638298 (1550 1200);
FORCEPROP 1 LAST $LOCATION C1932
J 0
(1550 1250);
DISPLAY 0.638298 (1550 1250);
FORCEPROP 1 LASTPIN (1500 1250) $PN 1
J 0
(1510 1230);
DISPLAY 0.510638 (1510 1230);
PAINT MONO (1510 1230);
FORCEPROP 1 LASTPIN (1500 1050) $PN 2
J 0
(1510 1030);
DISPLAY 0.510638 (1510 1030);
PAINT MONO (1510 1030);
FORCEPROP 2 LAST CDS_LIB pure_quanta
J 0
(1500 1150);
DISPLAY INVISIBLE (1500 1150);
FORCEPROP 1 LAST PATH I9
J 0
(1550 1300);
DISPLAY 0.978723 (1550 1300);
PAINT WHITE (1550 1300);
DISPLAY INVISIBLE (1550 1300);
FORCEPROP 2 LAST CDS_LOCATION C1932
J 0
(1550 1350);
DISPLAY 1.021277 (1550 1350);
DISPLAY INVISIBLE (1550 1350);
FORCEPROP 0 LAST $SEC 1
J 0
(1550 1300);
DISPLAY 0.680851 (1550 1300);
PAINT MONO (1550 1300);
DISPLAY INVISIBLE (1550 1300);
FORCEPROP 2 LAST CDS_SEC 1
J 0
(1550 1350);
DISPLAY 1.021277 (1550 1350);
DISPLAY INVISIBLE (1550 1350);
FORCEADD UNIVERSAL_POWER..1
(-6175 2425);
FORCEPROP 3 LASTPIN (-6175 2375) SIG_NAME VCC_PLD_CORE\g
J 0
(-6165 2385);
DISPLAY 0.659574 (-6165 2385);
PAINT MONO (-6165 2385);
DISPLAY INVISIBLE (-6165 2385);
FORCEPROP 1 LAST HDL_POWER VCC_PLD_CORE
J 1
(-6175 2475);
DISPLAY 0.872340 (-6175 2475);
PAINT GREEN (-6175 2475);
FORCEPROP 2 LAST CDS_LIB logical_power
J 0
(-6175 2425);
DISPLAY INVISIBLE (-6175 2425);
FORCEPROP 1 LAST PATH I92
J 0
(-6125 2450);
DISPLAY 0.872340 (-6125 2450);
PAINT AQUA (-6125 2450);
DISPLAY INVISIBLE (-6125 2450);
FORCEADD UNIVERSAL_POWER..1
(-3975 1725);
FORCEPROP 3 LASTPIN (-3975 1675) SIG_NAME P3V3_AUX_FPGA_VCCIO1\g
J 0
(-3965 1685);
DISPLAY 0.659574 (-3965 1685);
PAINT MONO (-3965 1685);
DISPLAY INVISIBLE (-3965 1685);
FORCEPROP 1 LAST HDL_POWER P3V3_AUX_FPGA_VCCIO1
J 1
(-3975 1775);
DISPLAY 0.872340 (-3975 1775);
PAINT GREEN (-3975 1775);
FORCEPROP 2 LAST CDS_LIB logical_power
J 0
(-3975 1725);
DISPLAY INVISIBLE (-3975 1725);
FORCEPROP 1 LAST PATH I93
J 0
(-3925 1750);
DISPLAY 0.872340 (-3925 1750);
PAINT AQUA (-3925 1750);
DISPLAY INVISIBLE (-3925 1750);
FORCEADD UNIVERSAL_POWER..1
(-3975 1050);
FORCEPROP 3 LASTPIN (-3975 1000) SIG_NAME P3V3_AUX_FPGA_VCCIO0\g
J 0
(-3965 1010);
DISPLAY 0.659574 (-3965 1010);
PAINT MONO (-3965 1010);
DISPLAY INVISIBLE (-3965 1010);
FORCEPROP 1 LAST HDL_POWER P3V3_AUX_FPGA_VCCIO0
J 1
(-3975 1100);
DISPLAY 0.872340 (-3975 1100);
PAINT GREEN (-3975 1100);
FORCEPROP 2 LAST CDS_LIB logical_power
J 0
(-3975 1050);
DISPLAY INVISIBLE (-3975 1050);
FORCEPROP 1 LAST PATH I94
J 0
(-3925 1075);
DISPLAY 0.872340 (-3925 1075);
PAINT AQUA (-3925 1075);
DISPLAY INVISIBLE (-3925 1075);
FORCEADD UNIVERSAL_POWER..1
(-3000 -1825);
FORCEPROP 3 LASTPIN (-3000 -1875) SIG_NAME P3V3_AUX\g
J 0
(-2990 -1865);
DISPLAY 0.659574 (-2990 -1865);
PAINT MONO (-2990 -1865);
DISPLAY INVISIBLE (-2990 -1865);
FORCEPROP 1 LAST HDL_POWER P3V3_AUX
J 1
(-3000 -1775);
DISPLAY 0.872340 (-3000 -1775);
PAINT GREEN (-3000 -1775);
FORCEPROP 2 LAST CDS_LIB logical_power
J 0
(-3000 -1825);
PAINT MONO (-3000 -1825);
DISPLAY INVISIBLE (-3000 -1825);
FORCEPROP 1 LAST PATH I95
J 0
(-2950 -1800);
DISPLAY 0.872340 (-2950 -1800);
PAINT AQUA (-2950 -1800);
DISPLAY INVISIBLE (-2950 -1800);
FORCEADD UNIVERSAL_POWER..1
(-3975 -1750);
FORCEPROP 3 LASTPIN (-3975 -1800) SIG_NAME P3V3_AUX_FPGA_VCCIO3\g
J 0
(-3965 -1790);
DISPLAY 0.659574 (-3965 -1790);
PAINT MONO (-3965 -1790);
DISPLAY INVISIBLE (-3965 -1790);
FORCEPROP 1 LAST HDL_POWER P3V3_AUX_FPGA_VCCIO3
J 1
(-3975 -1700);
DISPLAY 0.872340 (-3975 -1700);
PAINT GREEN (-3975 -1700);
FORCEPROP 2 LAST CDS_LIB logical_power
J 0
(-3975 -1750);
PAINT MONO (-3975 -1750);
DISPLAY INVISIBLE (-3975 -1750);
FORCEPROP 1 LAST PATH I96
J 0
(-3925 -1725);
DISPLAY 0.872340 (-3925 -1725);
PAINT AQUA (-3925 -1725);
DISPLAY INVISIBLE (-3925 -1725);
FORCEADD Q_CAP..1
(-3975 -2125);
FORCEPROP 1 LAST PART_NUMBER CH31006KB18
J 0
(-3925 -2275);
DISPLAY 0.510638 (-3925 -2275);
DISPLAY INVISIBLE (-3925 -2275);
FORCEPROP 1 LAST MATERIAL X7R
J 0
(-3925 -2225);
DISPLAY 0.510638 (-3925 -2225);
FORCEPROP 1 LAST VALUE 0.01UF
J 0
(-3925 -2075);
DISPLAY 0.510638 (-3925 -2075);
FORCEPROP 1 LAST PACK_TYPE C0402
J 0
(-3925 -2325);
DISPLAY 0.510638 (-3925 -2325);
FORCEPROP 1 LAST TOLERANCE 10%
J 0
(-3925 -2175);
DISPLAY 0.510638 (-3925 -2175);
FORCEPROP 1 LAST VOLTAGE 50V
J 0
(-3925 -2125);
DISPLAY 0.510638 (-3925 -2125);
FORCEPROP 1 LAST $LOCATION C1118
J 0
(-3925 -2025);
DISPLAY 0.510638 (-3925 -2025);
FORCEPROP 1 LASTPIN (-3975 -2025) $PN 1
J 0
(-3965 -2045);
DISPLAY 0.787234 (-3965 -2045);
PAINT MONO (-3965 -2045);
FORCEPROP 1 LASTPIN (-3975 -2225) $PN 2
J 0
(-3965 -2245);
DISPLAY 0.787234 (-3965 -2245);
PAINT MONO (-3965 -2245);
FORCEPROP 2 LAST CDS_LIB pure_quanta
J 0
(-3975 -2125);
DISPLAY INVISIBLE (-3975 -2125);
FORCEPROP 1 LAST PATH I97
J 0
(-3925 -1975);
DISPLAY 0.978723 (-3925 -1975);
PAINT WHITE (-3925 -1975);
DISPLAY INVISIBLE (-3925 -1975);
FORCEPROP 2 LAST CDS_LOCATION C1118
J 0
(-3925 -1925);
DISPLAY 1.021277 (-3925 -1925);
DISPLAY INVISIBLE (-3925 -1925);
FORCEPROP 0 LAST $SEC 1
J 0
(-3925 -2000);
DISPLAY 0.680851 (-3925 -2000);
PAINT MONO (-3925 -2000);
DISPLAY INVISIBLE (-3925 -2000);
FORCEPROP 2 LAST CDS_SEC 1
J 0
(-3925 -1925);
DISPLAY 1.021277 (-3925 -1925);
DISPLAY INVISIBLE (-3925 -1925);
FORCEADD UNIVERSAL_GND..1
(-3975 -2450);
FORCEPROP 3 LASTPIN (-3975 -2400) SIG_NAME GND\g
J 0
(-3965 -2390);
DISPLAY 0.659574 (-3965 -2390);
PAINT MONO (-3965 -2390);
DISPLAY INVISIBLE (-3965 -2390);
FORCEPROP 2 LAST CDS_LIB logical_power
J 0
(-3975 -2450);
DISPLAY INVISIBLE (-3975 -2450);
FORCEPROP 1 LAST HDL_POWER GND
J 1
(-3950 -2525);
DISPLAY 0.872340 (-3950 -2525);
PAINT GREEN (-3950 -2525);
DISPLAY INVISIBLE (-3950 -2525);
FORCEPROP 1 LAST PATH I98
J 0
(-3900 -2450);
DISPLAY 0.872340 (-3900 -2450);
PAINT AQUA (-3900 -2450);
DISPLAY INVISIBLE (-3900 -2450);
FORCEPROP 2 LAST ROOM IO_SLOT
J 1
(-4200 -2375);
DISPLAY 0.744681 (-4200 -2375);
DISPLAY INVISIBLE (-4200 -2375);
FORCEADD Q_CAP..1
(-4225 -2125);
FORCEPROP 1 LAST PART_NUMBER CH31006KB18
J 0
(-4175 -2275);
DISPLAY 0.319149 (-4175 -2275);
DISPLAY INVISIBLE (-4175 -2275);
FORCEPROP 1 LAST VOLTAGE 50V
J 0
(-4175 -2125);
DISPLAY 0.510638 (-4175 -2125);
FORCEPROP 1 LAST VALUE 0.01UF
J 0
(-4175 -2075);
DISPLAY 0.510638 (-4175 -2075);
FORCEPROP 1 LAST TOLERANCE 10%
J 0
(-4175 -2175);
DISPLAY 0.510638 (-4175 -2175);
FORCEPROP 1 LAST MATERIAL X7R
J 0
(-4175 -2225);
DISPLAY 0.510638 (-4175 -2225);
FORCEPROP 1 LAST PACK_TYPE C0402
J 0
(-4175 -2325);
DISPLAY 0.510638 (-4175 -2325);
FORCEPROP 1 LAST $LOCATION C1113
J 0
(-4175 -2025);
DISPLAY 0.510638 (-4175 -2025);
FORCEPROP 1 LASTPIN (-4225 -2025) $PN 1
J 0
(-4215 -2045);
DISPLAY 0.787234 (-4215 -2045);
PAINT MONO (-4215 -2045);
FORCEPROP 1 LASTPIN (-4225 -2225) $PN 2
J 0
(-4215 -2245);
DISPLAY 0.787234 (-4215 -2245);
PAINT MONO (-4215 -2245);
FORCEPROP 2 LAST CDS_LIB pure_quanta
J 0
(-4225 -2125);
DISPLAY INVISIBLE (-4225 -2125);
FORCEPROP 1 LAST PATH I99
J 0
(-4175 -1975);
DISPLAY 0.978723 (-4175 -1975);
PAINT WHITE (-4175 -1975);
DISPLAY INVISIBLE (-4175 -1975);
FORCEPROP 2 LAST CDS_LOCATION C1113
J 0
(-4175 -1925);
DISPLAY 1.021277 (-4175 -1925);
DISPLAY INVISIBLE (-4175 -1925);
FORCEPROP 0 LAST $SEC 1
J 0
(-4175 -2000);
DISPLAY 0.680851 (-4175 -2000);
PAINT MONO (-4175 -2000);
DISPLAY INVISIBLE (-4175 -2000);
FORCEPROP 2 LAST CDS_SEC 1
J 0
(-4175 -1925);
DISPLAY 1.021277 (-4175 -1925);
DISPLAY INVISIBLE (-4175 -1925);
FORCEADD QUANTA_TITLE_BLOCK_C..1
(2650 -3225);
FORCEPROP 0 LAST CDS_CON_LAST_MODIFIED Fri Aug 25 14:03:37 2023
J 0
(765 -3210);
DISPLAY INVISIBLE (765 -3210);
FORCEPROP 1 LAST CUSTOM_TXT_CDS <CON_LAST_MODIFIED>
J 0
(765 -3210);
DISPLAY 0.978723 (765 -3210);
FORCEPROP 2 LAST CUSTOM_TXT_CDS <XR_PAGE_TITLE>
J 0
(-5240 2025);
DISPLAY 0.638298 (-5240 2025);
PAINT PINK (-5240 2025);
DISPLAY INVISIBLE (-5240 2025);
FORCEPROP 1 LAST CUSTOM_TXT_CDS <NAME_2>
J 0
(-525 -3175);
FORCEPROP 1 LAST CUSTOM_TXT_CDS <NAME_1>
J 0
(-525 -3050);
FORCEPROP 1 LAST CUSTOM_TXT_CDS <Q_NUMBER>
J 0
(1247 -3122);
DISPLAY 1.212766 (1247 -3122);
FORCEPROP 1 LAST CUSTOM_TXT_CDS <Q_PROJ>
J 0
(268 -3123);
DISPLAY 1.212766 (268 -3123);
FORCEPROP 1 LAST CUSTOM_TXT_CDS <Q_REV>
J 0
(2466 -3122);
DISPLAY 1.212766 (2466 -3122);
FORCEPROP 1 LAST CUSTOM_TXT_CDS <CON_PAGE_NUM> OF <CON_TOTAL_PAGES>
J 0
(2204 -3207);
DISPLAY 0.978723 (2204 -3207);
FORCEPROP 1 LAST Q_TITLE MAIN FPGA / PFR (5/5)
J 0
(-6716 -3199);
DISPLAY 2.446809 (-6716 -3199);
PAINT GREEN (-6716 -3199);
FORCEPROP 1 LAST Q_DEPT 
J 1
(-1113 -3176);
DISPLAY 1.957447 (-1113 -3176);
PAINT GREEN (-1113 -3176);
FORCEPROP 2 LAST CDS_XR_PAGE_TITLE CR-217 : @S9S_MB_2U_LIB.S9S_MB_2U(SCH_1):PAGE217
J 0
(-5240 2025);
DISPLAY 0.638298 (-5240 2025);
PAINT PINK (-5240 2025);
DISPLAY INVISIBLE (-5240 2025);
FORCEPROP 1 LAST COMMENT_BODY TRUE
J 0
(2662 -3238);
DISPLAY 0.978723 (2662 -3238);
PAINT GREEN (2662 -3238);
DISPLAY INVISIBLE (2662 -3238);
FORCEPROP 2 LAST CDS_LIB pure_quanta
J 0
(2650 -3225);
DISPLAY INVISIBLE (2650 -3225);
FORCEPROP 1 LAST CDS_LMAN_SYM_OUTLINE -9475,6775,100,-125
J 0
(2650 -3225);
DISPLAY 0.468085 (2650 -3225);
PAINT GREEN (2650 -3225);
DISPLAY INVISIBLE (2650 -3225);
FORCEPROP 2 LAST PAGE_BORDER TRUE
J 0
(-5240 2025);
DISPLAY 0.638298 (-5240 2025);
PAINT PINK (-5240 2025);
DISPLAY INVISIBLE (-5240 2025);
WIRE 16 -1 (2200 2625)(2200 2575);
WIRE 16 -1 (-2050 2825)(-2050 2575);
WIRE 16 -1 (1500 1350)(1500 1425);
WIRE 16 -1 (1250 1350)(1500 1350);
WIRE 16 -1 (1500 1250)(1500 1350);
WIRE 16 -1 (-1900 1350)(-1900 1450);
WIRE 16 -1 (-1575 1350)(-1900 1350);
WIRE 16 -1 (1425 325)(1425 450);
WIRE 16 -1 (1175 325)(1425 325);
WIRE 16 -1 (1425 225)(1425 325);
WIRE 16 -1 (-1900 325)(-1900 425);
WIRE 16 -1 (-1575 325)(-1900 325);
WIRE 16 -1 (-1875 -800)(-1875 -700);
WIRE 16 -1 (-1550 -800)(-1875 -800);
WIRE 16 -1 (1450 -800)(1450 -675);
WIRE 16 -1 (1200 -800)(1450 -800);
WIRE 16 -1 (1450 -900)(1450 -800);
WIRE 16 -1 (1750 -2025)(1750 -1925);
WIRE 16 -1 (1500 -2025)(1750 -2025);
WIRE 16 -1 (1750 -2125)(1750 -2025);
WIRE 16 -1 (-5950 -1925)(-5950 -1825);
WIRE 16 -1 (-5625 -1925)(-5950 -1925);
WIRE 16 -1 (-3975 -1925)(-3975 -1800);
WIRE 16 -1 (-4225 -1925)(-3975 -1925);
WIRE 16 -1 (-3975 -2025)(-3975 -1925);
WIRE 16 -1 (-3000 -1975)(-3000 -1875);
WIRE 16 -1 (-2675 -1975)(-3000 -1975);
WIRE 16 -1 (-1225 -1975)(-1225 -1900);
WIRE 16 -1 (-1475 -1975)(-1225 -1975);
WIRE 16 -1 (-1225 -2075)(-1225 -1975);
WIRE 16 -1 (-225 -2025)(-225 -1925);
WIRE 16 -1 (100 -2025)(-225 -2025);
WIRE 16 -1 (-3975 1675)(-3975 1650);
WIRE 16 -1 (-6150 1650)(-6150 1675);
WIRE 16 -1 (-5725 1650)(-6150 1650);
WIRE 16 -1 (-6175 2350)(-6175 2375);
WIRE 16 -1 (-5725 2350)(-6175 2350);
WIRE 16 -1 (-3975 1000)(-3975 950);
WIRE 16 -1 (-6150 1450)(-6150 1475);
WIRE 16 -1 (-5725 1450)(-6150 1450);
WIRE 16 -1 (-6150 1150)(-6150 1175);
WIRE 16 -1 (-5725 1150)(-6150 1150);
WIRE 16 -1 (-6150 950)(-6150 975);
WIRE 16 -1 (-5725 950)(-6150 950);
WIRE 16 -1 (2200 2175)(2200 2075);
WIRE 16 -1 (1950 2175)(2200 2175);
WIRE 16 -1 (2200 2175)(2200 2275);
WIRE 16 -1 (1500 950)(1500 875);
WIRE 16 -1 (1500 950)(1250 950);
WIRE 16 -1 (1500 950)(1500 1050);
WIRE 16 -1 (1425 -75)(1425 -150);
WIRE 16 -1 (1425 -75)(1175 -75);
WIRE 16 -1 (1425 -75)(1425 25);
WIRE 16 -1 (1450 -1200)(1450 -1275);
WIRE 16 -1 (1450 -1200)(1200 -1200);
WIRE 16 -1 (1450 -1200)(1450 -1100);
WIRE 16 -1 (-3975 -2325)(-3975 -2400);
WIRE 16 -1 (-3975 -2325)(-4225 -2325);
WIRE 16 -1 (-3975 -2325)(-3975 -2225);
WIRE 16 -1 (-1225 -2375)(-1225 -2450);
WIRE 16 -1 (-1225 -2375)(-1475 -2375);
WIRE 16 -1 (-1225 -2375)(-1225 -2275);
WIRE 16 -1 (1750 -2425)(1750 -2500);
WIRE 16 -1 (1750 -2425)(1500 -2425);
WIRE 16 -1 (1750 -2425)(1750 -2325);
WIRE 16 -1 (-2400 -300)(-2400 -150);
WIRE 16 -1 (1250 950)(1250 1050);
WIRE 16 -1 (1000 950)(1000 1050);
WIRE 16 -1 (1250 950)(1000 950);
WIRE 16 -1 (1000 950)(750 950);
WIRE 16 -1 (750 950)(750 1050);
WIRE 16 -1 (750 950)(500 950);
WIRE 16 -1 (500 950)(500 1050);
WIRE 16 -1 (500 950)(250 950);
WIRE 16 -1 (250 950)(250 1050);
WIRE 16 -1 (250 950)(0 950);
WIRE 16 -1 (0 950)(0 1050);
WIRE 16 -1 (-250 1050)(-250 950);
WIRE 16 -1 (0 950)(-250 950);
WIRE 16 -1 (-250 950)(-525 950);
WIRE 16 -1 (-525 1050)(-525 950);
WIRE 16 -1 (-825 950)(-525 950);
WIRE 16 -1 (-825 1050)(-825 950);
WIRE 16 -1 (-1175 950)(-825 950);
WIRE 16 -1 (-1175 1075)(-1175 950);
WIRE 16 -1 (1250 1250)(1250 1350);
WIRE 16 -1 (1000 1250)(1000 1350);
WIRE 16 -1 (1000 1350)(1250 1350);
WIRE 16 -1 (750 1250)(750 1350);
WIRE 16 -1 (750 1350)(1000 1350);
WIRE 16 -1 (500 1250)(500 1350);
WIRE 16 -1 (500 1350)(750 1350);
WIRE 16 -1 (250 1250)(250 1350);
WIRE 16 -1 (250 1350)(500 1350);
WIRE 16 -1 (0 1350)(250 1350);
WIRE 16 -1 (0 1250)(0 1350);
WIRE 16 -1 (-250 1250)(-250 1350);
WIRE 16 -1 (-250 1350)(0 1350);
WIRE 16 -1 (-525 1250)(-525 1350);
WIRE 16 -1 (-525 1350)(-250 1350);
WIRE 16 -1 (-825 1250)(-825 1350);
WIRE 16 -1 (-825 1350)(-525 1350);
WIRE 16 -1 (-1175 1275)(-1175 1350);
WIRE 16 -1 (-1175 1350)(-825 1350);
WIRE 16 -1 (-1375 1350)(-1175 1350);
WIRE 16 -1 (-1600 2575)(-1275 2575);
WIRE 16 -1 (-1275 2500)(-1275 2575);
WIRE 16 -1 (-1275 2575)(-925 2575);
WIRE 16 -1 (-925 2500)(-925 2575);
WIRE 16 -1 (-575 2500)(-575 2575);
WIRE 16 -1 (-925 2575)(-575 2575);
WIRE 16 -1 (-300 2575)(-575 2575);
WIRE 16 -1 (-300 2475)(-300 2575);
WIRE 16 -1 (-50 2475)(-50 2575);
WIRE 16 -1 (-50 2575)(-300 2575);
WIRE 16 -1 (200 2575)(-50 2575);
WIRE 16 -1 (200 2475)(200 2575);
WIRE 16 -1 (450 2475)(450 2575);
WIRE 16 -1 (450 2575)(200 2575);
WIRE 16 -1 (700 2575)(450 2575);
WIRE 16 -1 (700 2475)(700 2575);
WIRE 16 -1 (950 2475)(950 2575);
WIRE 16 -1 (950 2575)(700 2575);
WIRE 16 -1 (1200 2575)(950 2575);
WIRE 16 -1 (1200 2475)(1200 2575);
WIRE 16 -1 (1450 2475)(1450 2575);
WIRE 16 -1 (1450 2575)(1200 2575);
WIRE 16 -1 (1700 2575)(1450 2575);
WIRE 16 -1 (1700 2475)(1700 2575);
WIRE 16 -1 (1950 2475)(1950 2575);
WIRE 16 -1 (1950 2575)(1700 2575);
WIRE 16 -1 (1950 2575)(2200 2575);
WIRE 16 -1 (2200 2475)(2200 2575);
WIRE 16 -1 (-2050 2575)(-1800 2575);
WIRE 16 -1 (1950 2175)(1950 2275);
WIRE 16 -1 (1700 2175)(1700 2275);
WIRE 16 -1 (1950 2175)(1700 2175);
WIRE 16 -1 (1450 2175)(1450 2275);
WIRE 16 -1 (1700 2175)(1450 2175);
WIRE 16 -1 (1200 2175)(1200 2275);
WIRE 16 -1 (1450 2175)(1200 2175);
WIRE 16 -1 (950 2175)(950 2275);
WIRE 16 -1 (1200 2175)(950 2175);
WIRE 16 -1 (700 2175)(700 2275);
WIRE 16 -1 (950 2175)(700 2175);
WIRE 16 -1 (450 2175)(450 2275);
WIRE 16 -1 (700 2175)(450 2175);
WIRE 16 -1 (200 2175)(200 2275);
WIRE 16 -1 (450 2175)(200 2175);
WIRE 16 -1 (-50 2175)(-50 2275);
WIRE 16 -1 (200 2175)(-50 2175);
WIRE 16 -1 (-300 2275)(-300 2175);
WIRE 16 -1 (-50 2175)(-300 2175);
WIRE 16 -1 (-575 2300)(-575 2175);
WIRE 16 -1 (-300 2175)(-575 2175);
WIRE 16 -1 (-925 2300)(-925 2175);
WIRE 16 -1 (-925 2175)(-575 2175);
WIRE 16 -1 (-1275 2175)(-925 2175);
WIRE 16 -1 (-1275 2300)(-1275 2175);
WIRE 16 -1 (-1375 325)(-1250 325);
WIRE 16 -1 (-1250 250)(-1250 325);
WIRE 16 -1 (-1250 325)(-900 325);
WIRE 16 -1 (-900 225)(-900 325);
WIRE 16 -1 (-900 325)(-600 325);
WIRE 16 -1 (-600 225)(-600 325);
WIRE 16 -1 (-600 325)(-325 325);
WIRE 16 -1 (-325 225)(-325 325);
WIRE 16 -1 (-325 325)(-75 325);
WIRE 16 -1 (-75 225)(-75 325);
WIRE 16 -1 (-75 325)(175 325);
WIRE 16 -1 (175 225)(175 325);
WIRE 16 -1 (175 325)(425 325);
WIRE 16 -1 (425 225)(425 325);
WIRE 16 -1 (425 325)(675 325);
WIRE 16 -1 (675 225)(675 325);
WIRE 16 -1 (675 325)(925 325);
WIRE 16 -1 (925 225)(925 325);
WIRE 16 -1 (925 325)(1175 325);
WIRE 16 -1 (1175 225)(1175 325);
WIRE 16 -1 (1175 -75)(1175 25);
WIRE 16 -1 (1175 -75)(925 -75);
WIRE 16 -1 (925 -75)(925 25);
WIRE 16 -1 (925 -75)(675 -75);
WIRE 16 -1 (675 -75)(675 25);
WIRE 16 -1 (675 -75)(425 -75);
WIRE 16 -1 (425 -75)(425 25);
WIRE 16 -1 (425 -75)(175 -75);
WIRE 16 -1 (175 -75)(175 25);
WIRE 16 -1 (-75 -75)(-75 25);
WIRE 16 -1 (175 -75)(-75 -75);
WIRE 16 -1 (-75 -75)(-325 -75);
WIRE 16 -1 (-325 25)(-325 -75);
WIRE 16 -1 (-325 -75)(-600 -75);
WIRE 16 -1 (-600 25)(-600 -75);
WIRE 16 -1 (-900 -75)(-600 -75);
WIRE 16 -1 (-900 25)(-900 -75);
WIRE 16 -1 (-1250 -75)(-900 -75);
WIRE 16 -1 (-1250 50)(-1250 -75);
WIRE 16 -1 (1200 -1200)(1200 -1100);
WIRE 16 -1 (950 -1200)(950 -1100);
WIRE 16 -1 (1200 -1200)(950 -1200);
WIRE 16 -1 (700 -1200)(700 -1100);
WIRE 16 -1 (950 -1200)(700 -1200);
WIRE 16 -1 (450 -1200)(450 -1100);
WIRE 16 -1 (700 -1200)(450 -1200);
WIRE 16 -1 (200 -1200)(200 -1100);
WIRE 16 -1 (450 -1200)(200 -1200);
WIRE 16 -1 (-50 -1200)(-50 -1100);
WIRE 16 -1 (200 -1200)(-50 -1200);
WIRE 16 -1 (-300 -1100)(-300 -1200);
WIRE 16 -1 (-50 -1200)(-300 -1200);
WIRE 16 -1 (-575 -1100)(-575 -1200);
WIRE 16 -1 (-300 -1200)(-575 -1200);
WIRE 16 -1 (-875 -1100)(-875 -1200);
WIRE 16 -1 (-875 -1200)(-575 -1200);
WIRE 16 -1 (-1225 -1200)(-875 -1200);
WIRE 16 -1 (-1225 -1075)(-1225 -1200);
WIRE 16 -1 (1200 -900)(1200 -800);
WIRE 16 -1 (950 -900)(950 -800);
WIRE 16 -1 (950 -800)(1200 -800);
WIRE 16 -1 (700 -900)(700 -800);
WIRE 16 -1 (700 -800)(950 -800);
WIRE 16 -1 (450 -900)(450 -800);
WIRE 16 -1 (450 -800)(700 -800);
WIRE 16 -1 (200 -900)(200 -800);
WIRE 16 -1 (200 -800)(450 -800);
WIRE 16 -1 (-50 -900)(-50 -800);
WIRE 16 -1 (-50 -800)(200 -800);
WIRE 16 -1 (-300 -900)(-300 -800);
WIRE 16 -1 (-300 -800)(-50 -800);
WIRE 16 -1 (-575 -900)(-575 -800);
WIRE 16 -1 (-575 -800)(-300 -800);
WIRE 16 -1 (-875 -900)(-875 -800);
WIRE 16 -1 (-875 -800)(-575 -800);
WIRE 16 -1 (-1225 -875)(-1225 -800);
WIRE 16 -1 (-1225 -800)(-875 -800);
WIRE 16 -1 (-1350 -800)(-1225 -800);
WIRE 16 -1 (-4225 -2025)(-4225 -1925);
WIRE 16 -1 (-4500 -2025)(-4500 -1925);
WIRE 16 -1 (-4500 -1925)(-4225 -1925);
WIRE 16 -1 (-4800 -2025)(-4800 -1925);
WIRE 16 -1 (-4800 -1925)(-4500 -1925);
WIRE 16 -1 (-5150 -2000)(-5150 -1925);
WIRE 16 -1 (-5150 -1925)(-4800 -1925);
WIRE 16 -1 (-5425 -1925)(-5150 -1925);
WIRE 16 -1 (-4225 -2225)(-4225 -2325);
WIRE 16 -1 (-4500 -2225)(-4500 -2325);
WIRE 16 -1 (-4225 -2325)(-4500 -2325);
WIRE 16 -1 (-4800 -2225)(-4800 -2325);
WIRE 16 -1 (-4800 -2325)(-4500 -2325);
WIRE 16 -1 (-5150 -2325)(-4800 -2325);
WIRE 16 -1 (-5150 -2200)(-5150 -2325);
WIRE 16 -1 (-1475 -2075)(-1475 -1975);
WIRE 16 -1 (-1750 -2075)(-1750 -1975);
WIRE 16 -1 (-1750 -1975)(-1475 -1975);
WIRE 16 -1 (-2050 -2075)(-2050 -1975);
WIRE 16 -1 (-2050 -1975)(-1750 -1975);
WIRE 16 -1 (-2475 -1975)(-2400 -1975);
WIRE 16 -1 (-2400 -1975)(-2050 -1975);
WIRE 16 -1 (-2400 -2050)(-2400 -1975);
WIRE 16 -1 (-2400 -2250)(-2400 -2375);
WIRE 16 -1 (-2400 -2375)(-2050 -2375);
WIRE 16 -1 (-2050 -2275)(-2050 -2375);
WIRE 16 -1 (-2050 -2375)(-1750 -2375);
WIRE 16 -1 (-1750 -2275)(-1750 -2375);
WIRE 16 -1 (-1475 -2375)(-1750 -2375);
WIRE 16 -1 (-1475 -2275)(-1475 -2375);
WIRE 16 -1 (1500 -2325)(1500 -2425);
WIRE 16 -1 (1225 -2325)(1225 -2425);
WIRE 16 -1 (1500 -2425)(1225 -2425);
WIRE 16 -1 (925 -2325)(925 -2425);
WIRE 16 -1 (925 -2425)(1225 -2425);
WIRE 16 -1 (575 -2425)(925 -2425);
WIRE 16 -1 (575 -2300)(575 -2425);
WIRE 16 -1 (1500 -2125)(1500 -2025);
WIRE 16 -1 (1225 -2125)(1225 -2025);
WIRE 16 -1 (1225 -2025)(1500 -2025);
WIRE 16 -1 (925 -2125)(925 -2025);
WIRE 16 -1 (925 -2025)(1225 -2025);
WIRE 16 -1 (300 -2025)(575 -2025);
WIRE 16 -1 (575 -2025)(925 -2025);
WIRE 16 -1 (575 -2100)(575 -2025);
WIRE 16 -1 (-2575 2400)(-2400 2400);
WIRE 16 -1 (-2575 2350)(-2400 2350);
WIRE 16 -1 (-2400 2400)(-2400 2350);
WIRE 16 -1 (-2575 2300)(-2400 2300);
WIRE 16 -1 (-2400 2350)(-2400 2300);
WIRE 16 -1 (-2575 2250)(-2400 2250);
WIRE 16 -1 (-2400 2300)(-2400 2250);
WIRE 16 -1 (-2400 2200)(-2575 2200);
WIRE 16 -1 (-2400 2250)(-2400 2200);
WIRE 16 -1 (-2400 2150)(-2575 2150);
WIRE 16 -1 (-2400 2200)(-2400 2150);
WIRE 16 -1 (-2400 2100)(-2575 2100);
WIRE 16 -1 (-2400 2150)(-2400 2100);
WIRE 16 -1 (-2400 2050)(-2575 2050);
WIRE 16 -1 (-2400 2100)(-2400 2050);
WIRE 16 -1 (-2400 2000)(-2575 2000);
WIRE 16 -1 (-2400 2050)(-2400 2000);
WIRE 16 -1 (-2400 1950)(-2575 1950);
WIRE 16 -1 (-2400 2000)(-2400 1950);
WIRE 16 -1 (-2400 1900)(-2575 1900);
WIRE 16 -1 (-2400 1950)(-2400 1900);
WIRE 16 -1 (-2400 1850)(-2575 1850);
WIRE 16 -1 (-2400 1900)(-2400 1850);
WIRE 16 -1 (-2400 1800)(-2575 1800);
WIRE 16 -1 (-2400 1850)(-2400 1800);
WIRE 16 -1 (-2400 1750)(-2575 1750);
WIRE 16 -1 (-2400 1800)(-2400 1750);
WIRE 16 -1 (-2400 1700)(-2575 1700);
WIRE 16 -1 (-2400 1750)(-2400 1700);
WIRE 16 -1 (-2400 1650)(-2575 1650);
WIRE 16 -1 (-2400 1700)(-2400 1650);
WIRE 16 -1 (-2400 1600)(-2575 1600);
WIRE 16 -1 (-2400 1650)(-2400 1600);
WIRE 16 -1 (-2400 1550)(-2575 1550);
WIRE 16 -1 (-2400 1600)(-2400 1550);
WIRE 16 -1 (-2400 1500)(-2575 1500);
WIRE 16 -1 (-2400 1550)(-2400 1500);
WIRE 16 -1 (-2400 1450)(-2575 1450);
WIRE 16 -1 (-2400 1500)(-2400 1450);
WIRE 16 -1 (-2400 1400)(-2575 1400);
WIRE 16 -1 (-2400 1450)(-2400 1400);
WIRE 16 -1 (-2400 1350)(-2575 1350);
WIRE 16 -1 (-2400 1400)(-2400 1350);
WIRE 16 -1 (-2400 1300)(-2575 1300);
WIRE 16 -1 (-2400 1350)(-2400 1300);
WIRE 16 -1 (-2400 1250)(-2575 1250);
WIRE 16 -1 (-2400 1300)(-2400 1250);
WIRE 16 -1 (-2400 1200)(-2575 1200);
WIRE 16 -1 (-2400 1250)(-2400 1200);
WIRE 16 -1 (-2400 1150)(-2575 1150);
WIRE 16 -1 (-2400 1200)(-2400 1150);
WIRE 16 -1 (-2400 1100)(-2575 1100);
WIRE 16 -1 (-2400 1150)(-2400 1100);
WIRE 16 -1 (-2400 1050)(-2575 1050);
WIRE 16 -1 (-2400 1100)(-2400 1050);
WIRE 16 -1 (-2400 1000)(-2575 1000);
WIRE 16 -1 (-2400 1050)(-2400 1000);
WIRE 16 -1 (-2400 950)(-2575 950);
WIRE 16 -1 (-2400 1000)(-2400 950);
WIRE 16 -1 (-2400 900)(-2575 900);
WIRE 16 -1 (-2400 950)(-2400 900);
WIRE 16 -1 (-2400 850)(-2575 850);
WIRE 16 -1 (-2400 900)(-2400 850);
WIRE 16 -1 (-2400 800)(-2575 800);
WIRE 16 -1 (-2400 850)(-2400 800);
WIRE 16 -1 (-2400 750)(-2575 750);
WIRE 16 -1 (-2400 800)(-2400 750);
WIRE 16 -1 (-2400 700)(-2575 700);
WIRE 16 -1 (-2400 750)(-2400 700);
WIRE 16 -1 (-2400 650)(-2575 650);
WIRE 16 -1 (-2400 700)(-2400 650);
WIRE 16 -1 (-2400 600)(-2575 600);
WIRE 16 -1 (-2400 650)(-2400 600);
WIRE 16 -1 (-2400 550)(-2575 550);
WIRE 16 -1 (-2400 550)(-2400 600);
WIRE 16 -1 (-2400 500)(-2575 500);
WIRE 16 -1 (-2400 550)(-2400 500);
WIRE 16 -1 (-2400 450)(-2575 450);
WIRE 16 -1 (-2400 500)(-2400 450);
WIRE 16 -1 (-2400 400)(-2575 400);
WIRE 16 -1 (-2400 450)(-2400 400);
WIRE 16 -1 (-2400 350)(-2575 350);
WIRE 16 -1 (-2400 400)(-2400 350);
WIRE 16 -1 (-2400 300)(-2575 300);
WIRE 16 -1 (-2400 350)(-2400 300);
WIRE 16 -1 (-2400 250)(-2575 250);
WIRE 16 -1 (-2400 300)(-2400 250);
WIRE 16 -1 (-2400 200)(-2575 200);
WIRE 16 -1 (-2400 250)(-2400 200);
WIRE 16 -1 (-2400 150)(-2575 150);
WIRE 16 -1 (-2400 200)(-2400 150);
WIRE 16 -1 (-2400 -150)(-2575 -150);
WIRE 16 -1 (-2400 100)(-2575 100);
WIRE 16 -1 (-2400 150)(-2400 100);
WIRE 16 -1 (-2400 50)(-2575 50);
WIRE 16 -1 (-2400 100)(-2400 50);
WIRE 16 -1 (-2400 -100)(-2575 -100);
WIRE 16 -1 (-2400 -100)(-2400 -150);
WIRE 16 -1 (-2400 -50)(-2575 -50);
WIRE 16 -1 (-2400 -50)(-2400 -100);
WIRE 16 -1 (-2400 50)(-2400 0);
WIRE 16 -1 (-2400 0)(-2575 0);
WIRE 16 -1 (-2400 0)(-2400 -50);
WIRE 16 -1 (-4175 1650)(-4400 1650);
WIRE 16 -1 (-4175 1650)(-3975 1650);
WIRE 16 -1 (-4175 1600)(-4400 1600);
WIRE 16 -1 (-4175 1600)(-4175 1650);
WIRE 16 -1 (-4400 1550)(-4175 1550);
WIRE 16 -1 (-4175 1550)(-4175 1600);
WIRE 16 -1 (-4175 1500)(-4400 1500);
WIRE 16 -1 (-4175 1500)(-4175 1550);
WIRE 16 -1 (-4175 1450)(-4400 1450);
WIRE 16 -1 (-4175 1450)(-4175 1500);
WIRE 16 -1 (-4400 1400)(-4175 1400);
WIRE 16 -1 (-4175 1400)(-4175 1450);
WIRE 16 -1 (-4175 1350)(-4400 1350);
WIRE 16 -1 (-4175 1350)(-4175 1400);
WIRE 16 -1 (-4175 1300)(-4400 1300);
WIRE 16 -1 (-4175 1300)(-4175 1350);
WIRE 16 -1 (-4175 1250)(-4175 1300);
WIRE 16 -1 (-4400 1250)(-4175 1250);
WIRE 16 -1 (-5500 1150)(-5725 1150);
WIRE 16 -1 (-5725 1150)(-5725 1100);
WIRE 16 -1 (-5500 1100)(-5725 1100);
WIRE 16 -1 (-5725 1100)(-5725 1050);
WIRE 16 -1 (-5725 1050)(-5500 1050);
WIRE 16 -1 (-5500 2350)(-5725 2350);
WIRE 16 -1 (-5725 2350)(-5725 2300);
WIRE 16 -1 (-5500 2300)(-5725 2300);
WIRE 16 -1 (-5725 2300)(-5725 2250);
WIRE 16 -1 (-5725 2250)(-5500 2250);
WIRE 16 -1 (-5725 2250)(-5725 2200);
WIRE 16 -1 (-5500 2200)(-5725 2200);
WIRE 16 -1 (-5725 2200)(-5725 2150);
WIRE 16 -1 (-5725 2150)(-5500 2150);
WIRE 16 -1 (-5725 2150)(-5725 2100);
WIRE 16 -1 (-5500 2100)(-5725 2100);
WIRE 16 -1 (-5725 2100)(-5725 2050);
WIRE 16 -1 (-5500 2050)(-5725 2050);
WIRE 16 -1 (-5725 2000)(-5500 2000);
WIRE 16 -1 (-5725 2050)(-5725 2000);
WIRE 16 -1 (-5725 2000)(-5725 1950);
WIRE 16 -1 (-5500 1950)(-5725 1950);
WIRE 16 -1 (-5725 1950)(-5725 1900);
WIRE 16 -1 (-5725 1900)(-5500 1900);
WIRE 16 -1 (-5725 1900)(-5725 1850);
WIRE 16 -1 (-5500 1850)(-5725 1850);
WIRE 16 -1 (-5725 1850)(-5725 1800);
WIRE 16 -1 (-5500 1800)(-5725 1800);
WIRE 16 -1 (-4400 550)(-4175 550);
WIRE 16 -1 (-4175 600)(-4400 600);
WIRE 16 -1 (-4175 550)(-4175 600);
WIRE 16 -1 (-4175 650)(-4400 650);
WIRE 16 -1 (-4175 600)(-4175 650);
WIRE 16 -1 (-4400 700)(-4175 700);
WIRE 16 -1 (-4175 650)(-4175 700);
WIRE 16 -1 (-4175 750)(-4400 750);
WIRE 16 -1 (-4175 700)(-4175 750);
WIRE 16 -1 (-4175 800)(-4400 800);
WIRE 16 -1 (-4175 750)(-4175 800);
WIRE 16 -1 (-4400 850)(-4175 850);
WIRE 16 -1 (-4175 800)(-4175 850);
WIRE 16 -1 (-4175 900)(-4400 900);
WIRE 16 -1 (-4175 850)(-4175 900);
WIRE 16 -1 (-4175 950)(-4400 950);
WIRE 16 -1 (-4175 900)(-4175 950);
WIRE 16 -1 (-4175 950)(-3975 950);
WIRE 16 -1 (-5500 950)(-5725 950);
WIRE 16 -1 (-5725 950)(-5725 900);
WIRE 16 -1 (-5500 900)(-5725 900);
WIRE 16 -1 (-5725 900)(-5725 850);
WIRE 16 -1 (-5725 850)(-5500 850);
WIRE 16 -1 (-5725 850)(-5725 800);
WIRE 16 -1 (-5500 800)(-5725 800);
WIRE 16 -1 (-5725 800)(-5725 750);
WIRE 16 -1 (-5500 750)(-5725 750);
WIRE 16 -1 (-5725 750)(-5725 700);
WIRE 16 -1 (-5725 700)(-5500 700);
WIRE 16 -1 (-5725 700)(-5725 650);
WIRE 16 -1 (-5500 650)(-5725 650);
WIRE 16 -1 (-5725 650)(-5725 600);
WIRE 16 -1 (-5500 600)(-5725 600);
WIRE 16 -1 (-5725 600)(-5725 550);
WIRE 16 -1 (-5725 550)(-5500 550);
WIRE 16 -1 (-5500 1450)(-5725 1450);
WIRE 16 -1 (-5725 1450)(-5725 1400);
WIRE 16 -1 (-5500 1400)(-5725 1400);
WIRE 16 -1 (-5725 1400)(-5725 1350);
WIRE 16 -1 (-5725 1350)(-5500 1350);
WIRE 16 -1 (-5500 1650)(-5725 1650);
WIRE 16 -1 (-5725 1650)(-5725 1600);
WIRE 16 -1 (-5500 1600)(-5725 1600);
WIRE 16 -1 (-5725 1600)(-5725 1550);
WIRE 16 -1 (-5725 1550)(-5500 1550);
DOT 1 (200 2175);
DOT 1 (-1275 2575);
DOT 1 (-575 2175);
DOT 1 (-925 2175);
DOT 1 (-925 2575);
DOT 1 (-575 2575);
DOT 1 (-300 2175);
DOT 1 (-50 2175);
DOT 1 (-300 2575);
DOT 1 (-50 2575);
DOT 1 (450 2175);
DOT 1 (200 2575);
DOT 1 (450 2575);
DOT 1 (700 2175);
DOT 1 (950 2175);
DOT 1 (700 2575);
DOT 1 (950 2575);
DOT 1 (1200 2175);
DOT 1 (1450 2175);
DOT 1 (1200 2575);
DOT 1 (1450 2575);
DOT 1 (1950 2175);
DOT 1 (1700 2175);
DOT 1 (1700 2575);
DOT 1 (1950 2575);
DOT 1 (2200 2175);
DOT 1 (2200 2575);
DOT 1 (1500 1350);
DOT 1 (1500 950);
DOT 1 (1250 1350);
DOT 1 (1250 950);
DOT 1 (1000 1350);
DOT 1 (1000 950);
DOT 1 (750 1350);
DOT 1 (750 950);
DOT 1 (500 1350);
DOT 1 (500 950);
DOT 1 (250 1350);
DOT 1 (250 950);
DOT 1 (0 1350);
DOT 1 (0 950);
DOT 1 (-250 1350);
DOT 1 (-250 950);
DOT 1 (-525 1350);
DOT 1 (-525 950);
DOT 1 (-825 1350);
DOT 1 (-825 950);
DOT 1 (-1175 1350);
DOT 1 (-1250 325);
DOT 1 (-900 -75);
DOT 1 (-600 -75);
DOT 1 (-325 -75);
DOT 1 (-75 -75);
DOT 1 (-75 325);
DOT 1 (-325 325);
DOT 1 (-600 325);
DOT 1 (-900 325);
DOT 1 (175 -75);
DOT 1 (425 -75);
DOT 1 (675 -75);
DOT 1 (925 -75);
DOT 1 (675 325);
DOT 1 (925 325);
DOT 1 (425 325);
DOT 1 (175 325);
DOT 1 (1175 -75);
DOT 1 (1425 -75);
DOT 1 (1175 325);
DOT 1 (1425 325);
DOT 1 (-875 -1200);
DOT 1 (-575 -1200);
DOT 1 (-300 -1200);
DOT 1 (-50 -1200);
DOT 1 (-1225 -800);
DOT 1 (-875 -800);
DOT 1 (-575 -800);
DOT 1 (-300 -800);
DOT 1 (-50 -800);
DOT 1 (200 -1200);
DOT 1 (450 -1200);
DOT 1 (700 -1200);
DOT 1 (950 -1200);
DOT 1 (1200 -1200);
DOT 1 (1450 -1200);
DOT 1 (200 -800);
DOT 1 (450 -800);
DOT 1 (700 -800);
DOT 1 (950 -800);
DOT 1 (1200 -800);
DOT 1 (1450 -800);
DOT 1 (-5150 -1925);
DOT 1 (-4800 -2325);
DOT 1 (-4800 -1925);
DOT 1 (-4500 -2325);
DOT 1 (-4500 -1925);
DOT 1 (-4225 -2325);
DOT 1 (-4225 -1925);
DOT 1 (-3975 -2325);
DOT 1 (-3975 -1925);
DOT 1 (-2400 -1975);
DOT 1 (-1750 -2375);
DOT 1 (-2050 -2375);
DOT 1 (-2050 -1975);
DOT 1 (-1750 -1975);
DOT 1 (-1225 -2375);
DOT 1 (-1475 -2375);
DOT 1 (-1475 -1975);
DOT 1 (-1225 -1975);
DOT 1 (925 -2425);
DOT 1 (575 -2025);
DOT 1 (925 -2025);
DOT 1 (1500 -2425);
DOT 1 (1225 -2425);
DOT 1 (1225 -2025);
DOT 1 (1500 -2025);
DOT 1 (1750 -2425);
DOT 1 (1750 -2025);
DOT 1 (-2400 -150);
DOT 1 (-2400 200);
DOT 1 (-2400 1050);
DOT 1 (-5725 1950);
DOT 1 (-2400 100);
DOT 1 (-2400 2350);
DOT 1 (-2400 2300);
DOT 1 (-2400 2250);
DOT 1 (-2400 2200);
DOT 1 (-2400 2150);
DOT 1 (-2400 2100);
DOT 1 (-2400 2050);
DOT 1 (-2400 2000);
DOT 1 (-2400 1950);
DOT 1 (-2400 1900);
DOT 1 (-2400 1850);
DOT 1 (-2400 1750);
DOT 1 (-2400 1800);
DOT 1 (-2400 1700);
DOT 1 (-2400 1650);
DOT 1 (-2400 1600);
DOT 1 (-2400 1500);
DOT 1 (-2400 1550);
DOT 1 (-2400 1450);
DOT 1 (-2400 1400);
DOT 1 (-2400 1350);
DOT 1 (-2400 1300);
DOT 1 (-2400 1250);
DOT 1 (-2400 1200);
DOT 1 (-2400 1150);
DOT 1 (-2400 1100);
DOT 1 (-2400 1000);
DOT 1 (-2400 950);
DOT 1 (-2400 850);
DOT 1 (-2400 900);
DOT 1 (-2400 800);
DOT 1 (-2400 750);
DOT 1 (-2400 700);
DOT 1 (-2400 650);
DOT 1 (-2400 600);
DOT 1 (-2400 550);
DOT 1 (-2400 500);
DOT 1 (-2400 450);
DOT 1 (-2400 400);
DOT 1 (-2400 350);
DOT 1 (-2400 300);
DOT 1 (-2400 250);
DOT 1 (-2400 150);
DOT 1 (-2400 50);
DOT 1 (-2400 0);
DOT 1 (-2400 -50);
DOT 1 (-2400 -100);
DOT 1 (-5725 2350);
DOT 1 (-5725 2300);
DOT 1 (-5725 2250);
DOT 1 (-4175 1600);
DOT 1 (-4175 1650);
DOT 1 (-4175 1550);
DOT 1 (-4175 1500);
DOT 1 (-4175 1450);
DOT 1 (-4175 1400);
DOT 1 (-4175 1350);
DOT 1 (-4175 1300);
DOT 1 (-4175 950);
DOT 1 (-4175 900);
DOT 1 (-4175 850);
DOT 1 (-4175 800);
DOT 1 (-4175 750);
DOT 1 (-4175 700);
DOT 1 (-4175 650);
DOT 1 (-4175 600);
DOT 1 (-5725 2200);
DOT 1 (-5725 2150);
DOT 1 (-5725 2100);
DOT 1 (-5725 2050);
DOT 1 (-5725 2000);
DOT 1 (-5725 1900);
DOT 1 (-5725 1850);
DOT 1 (-5725 1600);
DOT 1 (-5725 1650);
DOT 1 (-5725 1400);
DOT 1 (-5725 1450);
DOT 1 (-5725 1100);
DOT 1 (-5725 1150);
DOT 1 (-5725 950);
DOT 1 (-5725 850);
DOT 1 (-5725 900);
DOT 1 (-5725 800);
DOT 1 (-5725 750);
DOT 1 (-5725 700);
DOT 1 (-5725 600);
DOT 1 (-5725 650);
FORCENOTE
120OHM
(-1825 2450) 0;
DISPLAY LEFT (-1825 2450);
DISPLAY 0.638298 (-1825 2450);
PAINT ORANGE (-1825 2450);
FORCENOTE
20210902 MODIFY FOR GT
(-6600 3175) 0;
DISPLAY LEFT (-6600 3175);
DISPLAY 2.510638 (-6600 3175);
PAINT PINK (-6600 3175);
QUIT
